G04 ================== begin FILE IDENTIFICATION RECORD ==================*
G04 Layout Name:  9054_F0T_PDB_BD_GPU_F_V04_1213_1550.brd*
G04 Film Name:    sst*
G04 File Format:  Gerber RS274X*
G04 File Origin:  Cadence Allegro 17.2-S081*
G04 Origin Date:  Wed Dec 28 10:19:03 2022*
G04 *
G04 Layer:  DRAWING FORMAT/TITLE_BLOCK_A*
G04 Layer:  BOARD GEOMETRY/DESIGN_OUTLINE*
G04 Layer:  BOARD GEOMETRY/CUTOUT*
G04 Layer:  BOARD GEOMETRY/OUTLINE*
G04 Layer:  DRAWING FORMAT/TITLE_BLOCK*
G04 Layer:  MANUFACTURING/TP_TEXT_TOP*
G04 Layer:  REF DES/SILKSCREEN_TOP*
G04 Layer:  PACKAGE GEOMETRY/SILKSCREEN_TOP*
G04 Layer:  MANUFACTURING/PHOTOPLOT_OUTLINE*
G04 Layer:  DRAWING FORMAT/TITLE_DATA_SST*
G04 Layer:  BOARD GEOMETRY/SILKSCREEN_TOP*
G04 *
G04 Offset:    (0.00 0.00)*
G04 Mirror:    No*
G04 Mode:      Positive*
G04 Rotation:  0*
G04 FullContactRelief:  No*
G04 UndefLineWidth:     6.00*
G04 ================== end FILE IDENTIFICATION RECORD ====================*
%FSLAX25Y25*MOIN*%
%IR0*IPPOS*OFA0.00000B0.00000*MIA0B0*SFA1.00000B1.00000*%
%ADD10C,.01*%
%ADD11C,.07*%
%ADD12C,.006*%
%ADD13C,.075*%
G75*
%LPD*%
G75*
G36*
G01X203202Y215236D02*
G02X130368I-36417J0D01*
G01X203202D01*
G37*
G36*
G01Y295236D02*
G02X130368I-36417J0D01*
G01X203202D01*
G37*
G36*
G01Y375236D02*
G02X130368I-36417J0D01*
G01X203202D01*
G37*
G36*
G01Y455236D02*
G02X130368I-36417J0D01*
G01X203202D01*
G37*
G36*
G01Y535236D02*
G02X130368I-36417J0D01*
G01X203202D01*
G37*
G36*
G01X129239Y666185D02*
Y662185D01*
X133239Y664185D01*
X129239Y666185D01*
G37*
G36*
G01X280202Y215236D02*
G02X207368I-36417J0D01*
G01X280202D01*
G37*
G36*
G01Y295236D02*
G02X207368I-36417J0D01*
G01X280202D01*
G37*
G36*
G01Y375236D02*
G02X207368I-36417J0D01*
G01X280202D01*
G37*
G36*
G01Y455236D02*
G02X207368I-36417J0D01*
G01X280202D01*
G37*
G36*
G01Y535236D02*
G02X207368I-36417J0D01*
G01X280202D01*
G37*
G36*
G01X223441Y612576D02*
X220441Y605076D01*
X226441D01*
X223441Y612576D01*
G37*
G36*
G01X273676Y3000D02*
X274646Y4940D01*
X275616Y3000D01*
X273676D01*
G37*
G36*
G01X318091Y614441D02*
Y620441D01*
X312091Y617441D01*
X318091Y614441D01*
G37*
G36*
G01X374722Y183582D02*
X374222Y184132D01*
X378357Y188430D01*
X377868Y193860D01*
X374022Y197832D01*
X374272Y198532D01*
X374972Y198632D01*
X377693Y195804D01*
X377585Y197000D01*
X378825Y198000D01*
X379825Y198050D01*
X380775Y198500D01*
X382925D01*
X383475Y198250D01*
X384625Y197400D01*
X384825D01*
X385225Y197800D01*
X386025Y197700D01*
X386375Y197300D01*
Y196764D01*
X388172Y198632D01*
X388872Y198532D01*
X389122Y197832D01*
X386375Y194995D01*
Y193950D01*
X386125Y193650D01*
X385525D01*
X384929Y188283D01*
X385023Y188185D01*
X385075Y188150D01*
G02X385698Y187483I-1089J-1641D01*
G01X388922Y184132D01*
X388422Y183582D01*
X387772Y183632D01*
X385778Y185691D01*
G02X382325Y185450I-1792J818D01*
G01X378625D01*
X378498Y186860D01*
X375372Y183632D01*
X374722Y183582D01*
G37*
G36*
G01X375000Y183200D02*
X388150D01*
Y180900D01*
X375000D01*
Y183200D01*
G37*
G36*
G01X643941Y314738D02*
X641941Y310738D01*
X645941D01*
X643941Y314738D01*
G37*
G36*
G01X670500Y326914D02*
X669086Y325500D01*
X671207Y324793D01*
X670500Y326914D01*
G37*
G36*
G01X725559Y315262D02*
X727559Y319262D01*
X723559D01*
X725559Y315262D01*
G37*
G36*
G01X823900Y352238D02*
X827900D01*
X825900Y356238D01*
X823900Y352238D01*
G37*
G36*
G01X841787Y198984D02*
Y202984D01*
X837787Y200984D01*
X841787Y198984D01*
G37*
G36*
G01X868400Y392162D02*
X864400D01*
X866400Y388162D01*
X868400Y392162D01*
G37*
G36*
G01X904900Y352238D02*
X908900D01*
X906900Y356238D01*
X904900Y352238D01*
G37*
G36*
G01X959897Y198984D02*
Y202984D01*
X955897Y200984D01*
X959897Y198984D01*
G37*
G36*
G01X1463977Y2500D02*
X1465197Y4940D01*
X1466417Y2500D01*
X1463977D01*
G37*
G36*
G01X1524917Y215236D02*
G02X1452083I-36417J0D01*
G01X1524917D01*
G37*
G36*
G01Y295236D02*
G02X1452083I-36417J0D01*
G01X1524917D01*
G37*
G36*
G01Y375236D02*
G02X1452083I-36417J0D01*
G01X1524917D01*
G37*
G36*
G01Y455236D02*
G02X1452083I-36417J0D01*
G01X1524917D01*
G37*
G36*
G01Y535236D02*
G02X1452083I-36417J0D01*
G01X1524917D01*
G37*
G36*
G01X1480941Y607807D02*
X1486941D01*
X1483941Y613807D01*
X1480941Y607807D01*
G37*
G36*
G01X1601917Y215236D02*
G02X1529083I-36417J0D01*
G01X1601917D01*
G37*
G36*
G01Y295236D02*
G02X1529083I-36417J0D01*
G01X1601917D01*
G37*
G36*
G01Y375236D02*
G02X1529083I-36417J0D01*
G01X1601917D01*
G37*
G36*
G01Y455236D02*
G02X1529083I-36417J0D01*
G01X1601917D01*
G37*
G36*
G01Y535236D02*
G02X1529083I-36417J0D01*
G01X1601917D01*
G37*
G36*
G01X1539941Y614041D02*
X1536941Y606541D01*
X1542941D01*
X1539941Y614041D01*
G37*
G36*
G01X1570185Y672658D02*
X1566185D01*
X1568185Y668658D01*
X1570185Y672658D01*
G37*
G36*
G01X1649473Y85548D02*
Y74052D01*
X1646324D01*
Y85548D01*
X1649473D01*
G37*
G36*
G01X1643159Y182400D02*
X1641659Y185400D01*
X1644659D01*
X1643159Y182400D01*
G37*
G36*
G01X1652315Y121315D02*
X1653501Y124871D01*
X1655871Y122501D01*
X1652315Y121315D01*
G37*
G36*
G01X1680756Y119096D02*
X1665244D01*
Y121696D01*
X1680756D01*
Y119096D01*
G37*
G36*
G01X1689200Y85859D02*
X1686200Y84359D01*
Y87359D01*
X1689200Y85859D01*
G37*
G36*
G01X1731759Y136500D02*
X1730259Y139500D01*
X1733259D01*
X1731759Y136500D01*
G37*
G36*
G01X1732432Y170280D02*
X1734892D01*
X1733600Y168100D01*
X1732432Y170280D01*
G37*
G36*
G01X1731932Y154780D02*
X1734392D01*
X1733100Y152600D01*
X1731932Y154780D01*
G37*
G36*
G01X1724000Y190000D02*
X1726000D01*
X1725000Y192000D01*
X1724000Y190000D01*
G37*
G36*
G01X1730800Y181900D02*
Y179900D01*
X1733800Y180900D01*
X1730800Y181900D01*
G37*
G36*
G01X1768818Y326965D02*
Y330965D01*
X1764818Y328965D01*
X1768818Y326965D01*
G37*
G36*
G01X1870557Y312213D02*
Y316213D01*
X1866557Y314213D01*
X1870557Y312213D01*
G37*
%LPC*%
G75*
G36*
G01X381572Y191772D02*
X379206Y194231D01*
X379125Y195500D01*
X384025D01*
X383946Y194240D01*
X381572Y191772D01*
G37*
G36*
G01X380734Y190901D02*
X379501Y189619D01*
X379326Y192354D01*
X380734Y190901D01*
G37*
G36*
G01X383657Y189605D02*
X382410Y190901D01*
X383829Y192366D01*
X383657Y189605D01*
G37*
G36*
G01X383325Y188200D02*
G03X382025Y186850I849J-2119D01*
G01X379675Y186900D01*
X379604Y188003D01*
X381572Y190035D01*
X383342Y188207D01*
X383325Y188200D01*
G37*
G54D13*
X166785Y200472D03*
Y280472D03*
Y360472D03*
Y440472D03*
Y520472D03*
X243785Y200472D03*
Y280472D03*
Y360472D03*
Y440472D03*
Y520472D03*
X1488500Y200472D03*
Y280472D03*
Y360472D03*
Y440472D03*
Y520472D03*
X1565500Y200472D03*
Y280472D03*
Y360472D03*
Y440472D03*
Y520472D03*
%LPD*%
G75*
G36*
G01X380225Y194450D02*
X382925D01*
Y193700D01*
X380225D01*
Y194450D01*
G37*
G54D10*
G01X357000Y181300D02*
X358100Y181900D01*
Y176900D01*
G01X350500Y179600D02*
X355700D01*
X355600Y180300D01*
X355500Y180600D01*
X355300Y181000D01*
X355000Y181400D01*
X354500Y181800D01*
X354100Y182000D01*
X353800Y182100D01*
X353300Y182200D01*
X352900D01*
X352400Y182100D01*
X352100Y182000D01*
X351700Y181800D01*
X351300Y181500D01*
X351200Y181400D01*
X350900Y181000D01*
X350700Y180600D01*
X350600Y180300D01*
X350500Y179700D01*
Y179400D01*
X350600Y178900D01*
X350700Y178600D01*
X350900Y178200D01*
X351200Y177800D01*
X351700Y177400D01*
X352100Y177200D01*
X352400Y177100D01*
X353000Y177000D01*
X353100D01*
X353800Y177100D01*
X354100Y177200D01*
X354300Y177300D01*
X354900Y177700D01*
X355300Y178200D01*
G01X349800Y203400D02*
Y193300D01*
G01Y203400D02*
X352300D01*
G02Y198400I0J-2500D01*
G01X349800D01*
G01X355900Y203400D02*
Y193300D01*
G01X360710Y195700D02*
G03I-2410J0D01*
G54D11*
G01X758000Y26500D02*
X760500Y22499D01*
X763500Y19833D01*
X767000Y18500D01*
X771000Y19833D01*
X774000Y22499D01*
X777000Y26500D01*
X778000Y31833D01*
Y58500D01*
G01X798200Y18500D02*
X799200Y27166D01*
X800700Y34499D01*
X802700Y41167D01*
X805200Y48500D01*
X809200Y58500D01*
X789200D01*
G01X911000Y26000D02*
X913500Y21999D01*
X916500Y19333D01*
X920000Y18000D01*
X924000Y19333D01*
X927000Y21999D01*
X930000Y26000D01*
X931000Y31333D01*
Y58000D01*
G01X942700Y34666D02*
X946200Y39334D01*
X949200Y42000D01*
X953200Y43333D01*
X956700Y42000D01*
X959200Y39334D01*
X961200Y35333D01*
X961700Y30666D01*
X961200Y26666D01*
X959200Y22666D01*
X956200Y19333D01*
X952700Y18000D01*
X948700Y19333D01*
X945200Y23332D01*
X943200Y29333D01*
X942700Y36000D01*
X943700Y44666D01*
X945200Y49334D01*
X947700Y54000D01*
X951200Y57333D01*
X954700Y58000D01*
X958200Y56667D01*
X960700Y53333D01*
G54D12*
G01X-457143Y-1211429D02*
Y2242857D01*
X4308572D01*
Y-1211429D01*
X-457143D01*
G01X1874016Y85709D02*
Y499094D01*
G03X1854331Y518780I-19686J0D01*
G01X1751969D01*
G02X1732283Y538465I0J19686D01*
G01Y603543D01*
G03X1712598Y623228I-19685J0D01*
G01X1629921D01*
G02X1610236Y642913I0J19685D01*
G01Y656102D01*
G03X1590551Y675787I-19685J0D01*
G01X1437008D01*
G03X1417323Y656102I0J-19685D01*
G01Y635039D01*
G02X1405512Y623228I-11811J0D01*
G01X1403543D01*
G03X1383858Y603543I0J-19685D01*
G01Y435039D01*
G02X1354331Y405512I-29527J0D01*
G01X377953D01*
G02X348425Y435039I-1J29527D01*
G01Y603543D01*
G03X328740Y623228I-19685J0D01*
G01X326772D01*
G02X314961Y635039I0J11811D01*
G01Y656102D01*
G03X295276Y675787I-19685J0D01*
G01X141732D01*
G03X122047Y656102I0J-19685D01*
G01Y642913D01*
G02X102362Y623228I-19685J0D01*
G01X19685D01*
G03X0Y603543I0J-19685D01*
G01Y19685D01*
G03X19685Y0I19685J0D01*
G01X1712598D01*
G03X1732283Y19685I0J19685D01*
G01Y46339D01*
G02X1751969Y66024I19685J0D01*
G01X1854331D01*
G03X1874016Y85709I0J19685D01*
G01X37000Y-995000D02*
Y-1070000D01*
X537000D01*
Y-995000D01*
X37000D01*
G01X41339Y17717D02*
Y23763D01*
G03X38916Y32156I-15749J0D01*
G02X55572I8328J5245D01*
G03X53150Y23763I13326J-8392D01*
G01Y17717D01*
G02X41339I-5905J0D01*
G01Y23763D02*
G03X38916Y32156I-15749J0D01*
G02X55572I8328J5245D01*
G03X53150Y23763I13326J-8392D01*
G01Y17717D01*
G02X41339I-5905J0D01*
G01Y23763D01*
G01Y330709D02*
Y336756D01*
G03X38916Y345148I-15747J-1D01*
G02X55572I8328J5245D01*
G03X53150Y336756I13324J-8391D01*
G01Y330709D01*
G02X41339I-5905J0D01*
G01Y336756D02*
G03X38916Y345148I-15747J-1D01*
G02X55572I8328J5245D01*
G03X53150Y336756I13324J-8391D01*
G01Y330709D01*
G02X41339I-5905J0D01*
G01Y336756D01*
G01X19685Y541339D02*
G02X44882I12598J0D01*
G02X19685I-12599J0D01*
G01D02*
G02X44882I12598J0D01*
G02X19685I-12599J0D01*
G01X49000Y-1060000D02*
Y-1065000D01*
G01X47543Y-1060000D02*
X50457D01*
G01X55367Y-1065000D02*
X52833D01*
Y-1060000D01*
X55367D01*
G01X54353Y-1062417D02*
X52833D01*
G01X57933Y-1060000D02*
Y-1065000D01*
X60467D01*
G01X64300Y-1065167D02*
X64173Y-1065083D01*
Y-1064917D01*
X64300Y-1064833D01*
X64427Y-1064917D01*
Y-1065083D01*
X64300Y-1065167D01*
G01Y-1062917D02*
X64173Y-1062833D01*
Y-1062667D01*
X64300Y-1062583D01*
X64427Y-1062667D01*
Y-1062833D01*
X64300Y-1062917D01*
G01X69083Y-1066667D02*
X68450Y-1065833D01*
X68133Y-1065000D01*
Y-1061667D01*
X68450Y-1060833D01*
X69083Y-1060000D01*
G01X74500D02*
X73993Y-1060167D01*
X73613Y-1060583D01*
X73360Y-1061083D01*
X73170Y-1061750D01*
X73107Y-1062500D01*
X73170Y-1063250D01*
X73360Y-1063917D01*
X73613Y-1064417D01*
X73993Y-1064833D01*
X74500Y-1065000D01*
X75007Y-1064833D01*
X75387Y-1064417D01*
X75640Y-1063917D01*
X75830Y-1063250D01*
X75893Y-1062500D01*
X75830Y-1061750D01*
X75640Y-1061083D01*
X75387Y-1060583D01*
X75007Y-1060167D01*
X74500Y-1060000D01*
G01X78207Y-1064000D02*
X78587Y-1064583D01*
X79093Y-1064917D01*
X79663Y-1065000D01*
X80170Y-1064917D01*
X80677Y-1064500D01*
X80993Y-1064000D01*
X81057Y-1063500D01*
X80930Y-1062917D01*
X80487Y-1062500D01*
X80043Y-1062333D01*
X79473D01*
G01X80043D02*
X80423Y-1062083D01*
X80740Y-1061667D01*
X80867Y-1061167D01*
X80740Y-1060667D01*
X80423Y-1060250D01*
X79853Y-1060000D01*
X79283Y-1060083D01*
X78713Y-1060417D01*
G01X85017Y-1066667D02*
X85650Y-1065833D01*
X85967Y-1065000D01*
Y-1061667D01*
X85650Y-1060833D01*
X85017Y-1060000D01*
G01X88407Y-1064000D02*
X88787Y-1064583D01*
X89293Y-1064917D01*
X89863Y-1065000D01*
X90370Y-1064917D01*
X90877Y-1064500D01*
X91193Y-1064000D01*
X91257Y-1063500D01*
X91130Y-1062917D01*
X90687Y-1062500D01*
X90243Y-1062333D01*
X89673D01*
G01X90243D02*
X90623Y-1062083D01*
X90940Y-1061667D01*
X91067Y-1061167D01*
X90940Y-1060667D01*
X90623Y-1060250D01*
X90053Y-1060000D01*
X89483Y-1060083D01*
X88913Y-1060417D01*
G01X93697Y-1060833D02*
X94077Y-1060333D01*
X94520Y-1060083D01*
X95027Y-1060000D01*
X95660Y-1060167D01*
X96103Y-1060583D01*
X96230Y-1061083D01*
X96167Y-1061583D01*
X95913Y-1062000D01*
X94647Y-1062833D01*
X94077Y-1063417D01*
X93697Y-1064250D01*
X93570Y-1065000D01*
X96230D01*
G01X99873D02*
X100000Y-1063917D01*
X100190Y-1063000D01*
X100443Y-1062167D01*
X100760Y-1061250D01*
X101267Y-1060000D01*
X98733D01*
G01X104277Y-1063333D02*
X105923D01*
G01X108997Y-1060833D02*
X109377Y-1060333D01*
X109820Y-1060083D01*
X110327Y-1060000D01*
X110960Y-1060167D01*
X111403Y-1060583D01*
X111530Y-1061083D01*
X111467Y-1061583D01*
X111213Y-1062000D01*
X109947Y-1062833D01*
X109377Y-1063417D01*
X108997Y-1064250D01*
X108870Y-1065000D01*
X111530D01*
G01X113907Y-1064000D02*
X114287Y-1064583D01*
X114793Y-1064917D01*
X115363Y-1065000D01*
X115870Y-1064917D01*
X116377Y-1064500D01*
X116693Y-1064000D01*
X116757Y-1063500D01*
X116630Y-1062917D01*
X116187Y-1062500D01*
X115743Y-1062333D01*
X115173D01*
G01X115743D02*
X116123Y-1062083D01*
X116440Y-1061667D01*
X116567Y-1061167D01*
X116440Y-1060667D01*
X116123Y-1060250D01*
X115553Y-1060000D01*
X114983Y-1060083D01*
X114413Y-1060417D01*
G01X121160Y-1065000D02*
Y-1060000D01*
X118817Y-1063583D01*
X121983D01*
G01X124107Y-1064250D02*
X124487Y-1064667D01*
X124930Y-1064917D01*
X125500Y-1065000D01*
X126070Y-1064833D01*
X126513Y-1064500D01*
X126830Y-1063917D01*
X126893Y-1063250D01*
X126767Y-1062583D01*
X126450Y-1062167D01*
X126007Y-1061833D01*
X125563Y-1061750D01*
X125120Y-1061833D01*
X124550Y-1062167D01*
X124740Y-1060000D01*
X126450D01*
G01X134497Y-1065000D02*
Y-1060000D01*
X136903D01*
G01X136017Y-1062417D02*
X134497D01*
G01X139217Y-1065000D02*
X140800Y-1060000D01*
X142383Y-1065000D01*
G01X141813Y-1063250D02*
X139787D01*
G01X144570Y-1065000D02*
X147230Y-1060000D01*
G01X144570D02*
X147230Y-1065000D01*
G01X151000Y-1065167D02*
X150873Y-1065083D01*
Y-1064917D01*
X151000Y-1064833D01*
X151127Y-1064917D01*
Y-1065083D01*
X151000Y-1065167D01*
G01Y-1062917D02*
X150873Y-1062833D01*
Y-1062667D01*
X151000Y-1062583D01*
X151127Y-1062667D01*
Y-1062833D01*
X151000Y-1062917D01*
G01X155783Y-1066667D02*
X155150Y-1065833D01*
X154833Y-1065000D01*
Y-1061667D01*
X155150Y-1060833D01*
X155783Y-1060000D01*
G01X161200D02*
X160693Y-1060167D01*
X160313Y-1060583D01*
X160060Y-1061083D01*
X159870Y-1061750D01*
X159807Y-1062500D01*
X159870Y-1063250D01*
X160060Y-1063917D01*
X160313Y-1064417D01*
X160693Y-1064833D01*
X161200Y-1065000D01*
X161707Y-1064833D01*
X162087Y-1064417D01*
X162340Y-1063917D01*
X162530Y-1063250D01*
X162593Y-1062500D01*
X162530Y-1061750D01*
X162340Y-1061083D01*
X162087Y-1060583D01*
X161707Y-1060167D01*
X161200Y-1060000D01*
G01X164907Y-1064000D02*
X165287Y-1064583D01*
X165793Y-1064917D01*
X166363Y-1065000D01*
X166870Y-1064917D01*
X167377Y-1064500D01*
X167693Y-1064000D01*
X167757Y-1063500D01*
X167630Y-1062917D01*
X167187Y-1062500D01*
X166743Y-1062333D01*
X166173D01*
G01X166743D02*
X167123Y-1062083D01*
X167440Y-1061667D01*
X167567Y-1061167D01*
X167440Y-1060667D01*
X167123Y-1060250D01*
X166553Y-1060000D01*
X165983Y-1060083D01*
X165413Y-1060417D01*
G01X171717Y-1066667D02*
X172350Y-1065833D01*
X172667Y-1065000D01*
Y-1061667D01*
X172350Y-1060833D01*
X171717Y-1060000D01*
G01X175107Y-1064000D02*
X175487Y-1064583D01*
X175993Y-1064917D01*
X176563Y-1065000D01*
X177070Y-1064917D01*
X177577Y-1064500D01*
X177893Y-1064000D01*
X177957Y-1063500D01*
X177830Y-1062917D01*
X177387Y-1062500D01*
X176943Y-1062333D01*
X176373D01*
G01X176943D02*
X177323Y-1062083D01*
X177640Y-1061667D01*
X177767Y-1061167D01*
X177640Y-1060667D01*
X177323Y-1060250D01*
X176753Y-1060000D01*
X176183Y-1060083D01*
X175613Y-1060417D01*
G01X180523Y-1064417D02*
X180967Y-1064833D01*
X181473Y-1065000D01*
X181980Y-1064833D01*
X182423Y-1064333D01*
X182740Y-1063583D01*
X182867Y-1062833D01*
Y-1061917D01*
X182740Y-1061167D01*
X182423Y-1060500D01*
X182043Y-1060167D01*
X181600Y-1060000D01*
X181093Y-1060167D01*
X180713Y-1060500D01*
X180460Y-1061000D01*
X180333Y-1061667D01*
X180460Y-1062250D01*
X180777Y-1062833D01*
X181157Y-1063167D01*
X181600Y-1063250D01*
X182107Y-1063083D01*
X182487Y-1062667D01*
X182867Y-1061917D01*
G01X186573Y-1065000D02*
X186700Y-1063917D01*
X186890Y-1063000D01*
X187143Y-1062167D01*
X187460Y-1061250D01*
X187967Y-1060000D01*
X185433D01*
G01X190977Y-1063333D02*
X192623D01*
G01X195507Y-1064000D02*
X195887Y-1064583D01*
X196393Y-1064917D01*
X196963Y-1065000D01*
X197470Y-1064917D01*
X197977Y-1064500D01*
X198293Y-1064000D01*
X198357Y-1063500D01*
X198230Y-1062917D01*
X197787Y-1062500D01*
X197343Y-1062333D01*
X196773D01*
G01X197343D02*
X197723Y-1062083D01*
X198040Y-1061667D01*
X198167Y-1061167D01*
X198040Y-1060667D01*
X197723Y-1060250D01*
X197153Y-1060000D01*
X196583Y-1060083D01*
X196013Y-1060417D01*
G01X200797Y-1062917D02*
X201240Y-1062333D01*
X201620Y-1062000D01*
X202127Y-1061833D01*
X202570Y-1062000D01*
X202887Y-1062333D01*
X203140Y-1062833D01*
X203203Y-1063417D01*
X203140Y-1063917D01*
X202887Y-1064417D01*
X202507Y-1064833D01*
X202063Y-1065000D01*
X201557Y-1064833D01*
X201113Y-1064333D01*
X200860Y-1063583D01*
X200797Y-1062750D01*
X200923Y-1061667D01*
X201113Y-1061083D01*
X201430Y-1060500D01*
X201873Y-1060083D01*
X202317Y-1060000D01*
X202760Y-1060167D01*
X203077Y-1060583D01*
G01X207100Y-1065000D02*
Y-1060000D01*
X206340Y-1061000D01*
G01Y-1065000D02*
X207860D01*
G01X212960D02*
Y-1060000D01*
X210617Y-1063583D01*
X213783D01*
G01X51181Y236614D02*
G02X66929I7874J0D01*
G02X51181I-7874J0D01*
G01D02*
G02X66929I7874J0D01*
G02X51181I-7874J0D01*
G01Y411614D02*
G02X66929I7874J0D01*
G02X51181I-7874J0D01*
G01D02*
G02X66929I7874J0D01*
G02X51181I-7874J0D01*
G01X46457Y498031D02*
G02X71654I12598J0D01*
G02X46457I-12599J0D01*
G01D02*
G02X71654I12598J0D01*
G02X46457I-12599J0D01*
G01X203691Y639094D02*
G02X212057I4183J0D01*
G02X203691I-4183J0D01*
G01D02*
G02X212057I4183J0D01*
G02X203691I-4183J0D01*
G01X232000Y-995000D02*
Y-1070000D01*
G01Y-1045000D02*
X335000D01*
Y-1020000D01*
G01X232000D02*
X335000D01*
G01X236142Y15512D02*
G02X245591I4724J0D01*
G02X236142I-4724J0D01*
G01D02*
G02X245591I4724J0D01*
G02X236142I-4724J0D01*
G01X273622Y53150D02*
Y59196D01*
G03X271199Y67589I-15749J0D01*
G02X287856I8329J5246D01*
G03X285433Y59196I13326J-8393D01*
G01Y53150D01*
G02X273622I-5905J0D01*
G01Y59196D02*
G03X271199Y67589I-15749J0D01*
G02X287856I8329J5246D01*
G03X285433Y59196I13326J-8393D01*
G01Y53150D01*
G02X273622I-5905J0D01*
G01Y59196D01*
G01X283268Y628465D02*
G02X291535I4134J0D01*
G02X283268I-4134J0D01*
G01D02*
G02X291535I4134J0D01*
G02X283268I-4134J0D01*
G01X259646Y659961D02*
G02X267913I4134J0D01*
G02X259646I-4134J0D01*
G01D02*
G02X267913I4134J0D01*
G02X259646I-4134J0D01*
G01X296142Y10197D02*
G02X305591I4725J0D01*
G02X296142I-4724J0D01*
G01D02*
G02X305591I4725J0D01*
G02X296142I-4724J0D01*
G01X309678Y253631D02*
X313319Y257124D01*
G01X309494Y253681D02*
X313052Y257094D01*
G01X309311Y253733D02*
X312784Y257065D01*
G01X309126Y253783D02*
X312516Y257035D01*
G01X308942Y253833D02*
X312278Y257034D01*
G01X308758Y253885D02*
X312069Y257060D01*
G01X308574Y253935D02*
X311859Y257086D01*
G01X308399Y253995D02*
X311649Y257112D01*
G01X308232Y254061D02*
X311439Y257138D01*
G01X308064Y254127D02*
X311245Y257179D01*
G01X307897Y254194D02*
X311077Y257244D01*
G01X307729Y254260D02*
X310908Y257310D01*
G01X307562Y254327D02*
X310740Y257375D01*
G01X307394Y254393D02*
X310571Y257441D01*
G01X307243Y254475D02*
X310402Y257506D01*
G01X307092Y254558D02*
X310249Y257587D01*
G01X306941Y254640D02*
X310110Y257681D01*
G01X306790Y254723D02*
X309972Y257775D01*
G01X306639Y254806D02*
X309833Y257869D01*
G01X306488Y254888D02*
X309694Y257963D01*
G01X306343Y254976D02*
X309555Y258057D01*
G01X306208Y255074D02*
X309421Y258155D01*
G01X306074Y255172D02*
X309306Y258272D01*
G01X305939Y255269D02*
X309191Y258390D01*
G01X305804Y255368D02*
X309077Y258507D01*
G01X305670Y255465D02*
X308963Y258624D01*
G01X305535Y255564D02*
X308848Y258742D01*
G01X305409Y255670D02*
X308734Y258859D01*
G01X305290Y255784D02*
X308631Y258988D01*
G01X305171Y255896D02*
X308538Y259126D01*
G01X305052Y256009D02*
X308446Y259265D01*
G01X304933Y256122D02*
X308353Y259403D01*
G01X304814Y256235D02*
X308260Y259541D01*
G01X304694Y256348D02*
X308168Y259680D01*
G01X304587Y256473D02*
X308075Y259818D01*
G01X304486Y256602D02*
X308001Y259975D01*
G01X304384Y256732D02*
X307931Y260134D01*
G01X304283Y256862D02*
X307860Y260293D01*
G01X304182Y256992D02*
X307789Y260453D01*
G01X304080Y257122D02*
X307718Y260612D01*
G01X303979Y257252D02*
X307647Y260771D01*
G01X303887Y257391D02*
X307586Y260939D01*
G01X303805Y257539D02*
X307539Y261121D01*
G01X303722Y257687D02*
X307492Y261305D01*
G01X303639Y257835D02*
X307446Y261487D01*
G01X303557Y257983D02*
X307400Y261669D01*
G01X303474Y258131D02*
X307353Y261852D01*
G01X303392Y258279D02*
X307315Y262043D01*
G01X303322Y258440D02*
X307299Y262255D01*
G01X303257Y258604D02*
X307282Y262466D01*
G01X303191Y258768D02*
X307266Y262677D01*
G01X303125Y258932D02*
X307250Y262889D01*
G01X303059Y259096D02*
X307233Y263100D01*
G01X302994Y259261D02*
X307252Y263345D01*
G01X302937Y259433D02*
X307278Y263597D01*
G01X302886Y259612D02*
X307305Y263850D01*
G01X302835Y259790D02*
X307331Y264103D01*
G01X302785Y259969D02*
X307358Y264356D01*
G01X302734Y260148D02*
X307445Y264667D01*
G01X302684Y260327D02*
X307541Y264986D01*
G01X302646Y260518D02*
X307638Y265306D01*
G01X302609Y260710D02*
X307783Y265673D01*
G01X302572Y260901D02*
X308019Y266126D01*
G01X302535Y261093D02*
X308332Y266653D01*
G01X314347Y272652D02*
X302499Y261286D01*
G01X314138Y272677D02*
X302474Y261489D01*
G01X313928Y272703D02*
X302450Y261692D01*
G01X309678Y253631D02*
X313319Y257124D01*
G01X309494Y253681D02*
X313052Y257094D01*
G01X309311Y253733D02*
X312784Y257065D01*
G01X309126Y253783D02*
X312516Y257035D01*
G01X308942Y253833D02*
X312278Y257034D01*
G01X308758Y253885D02*
X312069Y257060D01*
G01X308574Y253935D02*
X311859Y257086D01*
G01X308399Y253995D02*
X311649Y257112D01*
G01X308232Y254061D02*
X311439Y257138D01*
G01X308064Y254127D02*
X311245Y257179D01*
G01X307897Y254194D02*
X311077Y257244D01*
G01X307729Y254260D02*
X310908Y257310D01*
G01X307562Y254327D02*
X310740Y257375D01*
G01X307394Y254393D02*
X310571Y257441D01*
G01X307243Y254475D02*
X310402Y257506D01*
G01X307092Y254558D02*
X310249Y257587D01*
G01X306941Y254640D02*
X310110Y257681D01*
G01X306790Y254723D02*
X309972Y257775D01*
G01X306639Y254806D02*
X309833Y257869D01*
G01X306488Y254888D02*
X309694Y257963D01*
G01X306343Y254976D02*
X309555Y258057D01*
G01X306208Y255074D02*
X309421Y258155D01*
G01X306074Y255172D02*
X309306Y258272D01*
G01X305939Y255269D02*
X309191Y258390D01*
G01X305804Y255368D02*
X309077Y258507D01*
G01X305670Y255465D02*
X308963Y258624D01*
G01X305535Y255564D02*
X308848Y258742D01*
G01X305409Y255670D02*
X308734Y258859D01*
G01X305290Y255784D02*
X308631Y258988D01*
G01X305171Y255896D02*
X308538Y259126D01*
G01X305052Y256009D02*
X308446Y259265D01*
G01X304933Y256122D02*
X308353Y259403D01*
G01X304814Y256235D02*
X308260Y259541D01*
G01X304694Y256348D02*
X308168Y259680D01*
G01X304587Y256473D02*
X308075Y259818D01*
G01X304486Y256602D02*
X308001Y259975D01*
G01X304384Y256732D02*
X307931Y260134D01*
G01X304283Y256862D02*
X307860Y260293D01*
G01X304182Y256992D02*
X307789Y260453D01*
G01X304080Y257122D02*
X307718Y260612D01*
G01X303979Y257252D02*
X307647Y260771D01*
G01X303887Y257391D02*
X307586Y260939D01*
G01X303805Y257539D02*
X307539Y261121D01*
G01X303722Y257687D02*
X307492Y261305D01*
G01X303639Y257835D02*
X307446Y261487D01*
G01X303557Y257983D02*
X307400Y261669D01*
G01X303474Y258131D02*
X307353Y261852D01*
G01X303392Y258279D02*
X307315Y262043D01*
G01X303322Y258440D02*
X307299Y262255D01*
G01X303257Y258604D02*
X307282Y262466D01*
G01X303191Y258768D02*
X307266Y262677D01*
G01X303125Y258932D02*
X307250Y262889D01*
G01X303059Y259096D02*
X307233Y263100D01*
G01X302994Y259261D02*
X307252Y263345D01*
G01X302937Y259433D02*
X307278Y263597D01*
G01X302886Y259612D02*
X307305Y263850D01*
G01X302835Y259790D02*
X307331Y264103D01*
G01X302785Y259969D02*
X307358Y264356D01*
G01X302734Y260148D02*
X307445Y264667D01*
G01X302684Y260327D02*
X307541Y264986D01*
G01X302646Y260518D02*
X307638Y265306D01*
G01X302609Y260710D02*
X307783Y265673D01*
G01X302572Y260901D02*
X308019Y266126D01*
G01X302535Y261093D02*
X308332Y266653D01*
G01X314347Y272652D02*
X302499Y261286D01*
G01X314138Y272677D02*
X302474Y261489D01*
G01X313928Y272703D02*
X302450Y261692D01*
G01X313718Y272730D02*
X302425Y261896D01*
G01X313498Y272746D02*
X302399Y262099D01*
G01X313270Y272755D02*
X302386Y262313D01*
G01X313043Y272764D02*
X302372Y262527D01*
G01X312815Y272772D02*
X302358Y262740D01*
G01X312588Y272781D02*
X302351Y262962D01*
G01X312342Y272772D02*
X302347Y263184D01*
G01X312094Y272762D02*
X302352Y263416D01*
G01X311845Y272750D02*
X302363Y263654D01*
G01X311596Y272739D02*
X302374Y263892D01*
G01X311348Y272728D02*
X302385Y264130D01*
G01X311071Y272689D02*
X302419Y264389D01*
G01X310793Y272650D02*
X302456Y264652D01*
G01X310515Y272611D02*
X302493Y264915D01*
G01X310238Y272572D02*
X302547Y265194D01*
G01X309926Y272500D02*
X302617Y265488D01*
G01X309610Y272423D02*
X302687Y265782D01*
G01X309292Y272346D02*
X302783Y266102D01*
G01X308946Y272242D02*
X302897Y266438D01*
G01X308573Y272110D02*
X303015Y266779D01*
G01X308198Y271978D02*
X303194Y267177D01*
G01X307743Y271769D02*
X303375Y267578D01*
G01X307275Y271548D02*
X303658Y268077D01*
G01X313718Y272730D02*
X302425Y261896D01*
G01X313498Y272746D02*
X302399Y262099D01*
G01X313270Y272755D02*
X302386Y262313D01*
G01X313043Y272764D02*
X302372Y262527D01*
G01X312815Y272772D02*
X302358Y262740D01*
G01X312588Y272781D02*
X302351Y262962D01*
G01X312342Y272772D02*
X302347Y263184D01*
G01X312094Y272762D02*
X302352Y263416D01*
G01X311845Y272750D02*
X302363Y263654D01*
G01X311596Y272739D02*
X302374Y263892D01*
G01X311348Y272728D02*
X302385Y264130D01*
G01X311071Y272689D02*
X302419Y264389D01*
G01X310793Y272650D02*
X302456Y264652D01*
G01X310515Y272611D02*
X302493Y264915D01*
G01X310238Y272572D02*
X302547Y265194D01*
G01X309926Y272500D02*
X302617Y265488D01*
G01X309610Y272423D02*
X302687Y265782D01*
G01X309292Y272346D02*
X302783Y266102D01*
G01X308946Y272242D02*
X302897Y266438D01*
G01X308573Y272110D02*
X303015Y266779D01*
G01X308198Y271978D02*
X303194Y267177D01*
G01X307743Y271769D02*
X303375Y267578D01*
G01X307275Y271548D02*
X303658Y268077D01*
G01X316606Y252324D02*
X318919Y254543D01*
G01X316435Y252387D02*
X318783Y254639D01*
G01X318647Y254736D02*
X316265Y252452D01*
G01X316095Y252516D02*
X318511Y254833D01*
G01X315925Y252580D02*
X320998Y257446D01*
G01X315754Y252642D02*
X321288Y257952D01*
G01X315583Y252706D02*
X321537Y258418D01*
G01X315411Y252768D02*
X321684Y258786D01*
G01X315239Y252831D02*
X321830Y259153D01*
G01X315067Y252892D02*
X321958Y259503D01*
G01X314893Y252953D02*
X322035Y259804D01*
G01X314719Y253014D02*
X322112Y260106D01*
G01X314543Y253071D02*
X322189Y260406D01*
G01X314366Y253128D02*
X322258Y260700D01*
G01X314183Y253182D02*
X322294Y260962D01*
G01X313983Y253216D02*
X322331Y261224D01*
G01X313753Y253223D02*
X322367Y261486D01*
G01X313523Y253228D02*
X322403Y261747D01*
G01X313293Y253236D02*
X322439Y262009D01*
G01X313063Y253242D02*
X322448Y262246D01*
G01X312832Y253249D02*
X322458Y262482D01*
G01X312602Y253255D02*
X322468Y262718D01*
G01X312377Y253266D02*
X322478Y262956D01*
G01X312162Y253287D02*
X322488Y263193D01*
G01X311946Y253307D02*
X322498Y263429D01*
G01X311730Y253327D02*
X322494Y263652D01*
G01X311515Y253348D02*
X322485Y263872D01*
G01X311299Y253368D02*
X322470Y264084D01*
G01X311083Y253388D02*
X322449Y264292D01*
G01X310879Y253418D02*
X322429Y264499D01*
G01X322403Y264701D02*
X310678Y253453D01*
G01X322370Y264897D02*
X316431Y259199D01*
G01X310478Y253489D02*
X314932Y257762D01*
G01X310278Y253524D02*
X314365Y257445D01*
G01X310078Y253559D02*
X313995Y257318D01*
G01X309877Y253594D02*
X313624Y257189D01*
G01X316606Y252324D02*
X318919Y254543D01*
G01X316435Y252387D02*
X318783Y254639D01*
G01X318647Y254736D02*
X316265Y252452D01*
G01X316095Y252516D02*
X318511Y254833D01*
G01X315925Y252580D02*
X320998Y257446D01*
G01X315754Y252642D02*
X321288Y257952D01*
G01X315583Y252706D02*
X321537Y258418D01*
G01X315411Y252768D02*
X321684Y258786D01*
G01X315239Y252831D02*
X321830Y259153D01*
G01X315067Y252892D02*
X321958Y259503D01*
G01X314893Y252953D02*
X322035Y259804D01*
G01X314719Y253014D02*
X322112Y260106D01*
G01X314543Y253071D02*
X322189Y260406D01*
G01X314366Y253128D02*
X322258Y260700D01*
G01X314183Y253182D02*
X322294Y260962D01*
G01X313983Y253216D02*
X322331Y261224D01*
G01X313753Y253223D02*
X322367Y261486D01*
G01X313523Y253228D02*
X322403Y261747D01*
G01X313293Y253236D02*
X322439Y262009D01*
G01X313063Y253242D02*
X322448Y262246D01*
G01X312832Y253249D02*
X322458Y262482D01*
G01X312602Y253255D02*
X322468Y262718D01*
G01X312377Y253266D02*
X322478Y262956D01*
G01X312162Y253287D02*
X322488Y263193D01*
G01X311946Y253307D02*
X322498Y263429D01*
G01X311730Y253327D02*
X322494Y263652D01*
G01X311515Y253348D02*
X322485Y263872D01*
G01X311299Y253368D02*
X322470Y264084D01*
G01X311083Y253388D02*
X322449Y264292D01*
G01X310879Y253418D02*
X322429Y264499D01*
G01X322403Y264701D02*
X310678Y253453D01*
G01X322370Y264897D02*
X316431Y259199D01*
G01X310478Y253489D02*
X314932Y257762D01*
G01X310278Y253524D02*
X314365Y257445D01*
G01X310078Y253559D02*
X313995Y257318D01*
G01X309877Y253594D02*
X313624Y257189D01*
G01X320103Y269766D02*
X316611Y266416D01*
G01X319993Y269887D02*
X316515Y266551D01*
G01X319883Y270009D02*
X316419Y266686D01*
G01X319763Y270121D02*
X316323Y266821D01*
G01X319638Y270229D02*
X316227Y266956D01*
G01X319512Y270336D02*
X316131Y267091D01*
G01X319388Y270443D02*
X316035Y267227D01*
G01X319262Y270549D02*
X315917Y267341D01*
G01X319137Y270656D02*
X315798Y267453D01*
G01X319004Y270757D02*
X315679Y267567D01*
G01X318867Y270852D02*
X315559Y267679D01*
G01X318730Y270947D02*
X315441Y267793D01*
G01X318593Y271043D02*
X315321Y267905D01*
G01X318455Y271139D02*
X315189Y268005D01*
G01X318318Y271234D02*
X315045Y268095D01*
G01X318171Y271320D02*
X314901Y268183D01*
G01X318021Y271404D02*
X314757Y268273D01*
G01X317871Y271487D02*
X314613Y268362D01*
G01X317721Y271571D02*
X314468Y268450D01*
G01X314558Y272626D02*
X309950Y268206D01*
G01X320103Y269766D02*
X316611Y266416D01*
G01X319993Y269887D02*
X316515Y266551D01*
G01X319883Y270009D02*
X316419Y266686D01*
G01X319763Y270121D02*
X316323Y266821D01*
G01X319638Y270229D02*
X316227Y266956D01*
G01X319512Y270336D02*
X316131Y267091D01*
G01X319388Y270443D02*
X316035Y267227D01*
G01X319262Y270549D02*
X315917Y267341D01*
G01X319137Y270656D02*
X315798Y267453D01*
G01X319004Y270757D02*
X315679Y267567D01*
G01X318867Y270852D02*
X315559Y267679D01*
G01X318730Y270947D02*
X315441Y267793D01*
G01X318593Y271043D02*
X315321Y267905D01*
G01X318455Y271139D02*
X315189Y268005D01*
G01X318318Y271234D02*
X315045Y268095D01*
G01X318171Y271320D02*
X314901Y268183D01*
G01X318021Y271404D02*
X314757Y268273D01*
G01X317871Y271487D02*
X314613Y268362D01*
G01X317721Y271571D02*
X314468Y268450D01*
G01X314558Y272626D02*
X309950Y268206D01*
G01X306647Y271172D02*
X304038Y268669D01*
G01X306647Y271172D02*
X304038Y268669D01*
G01X317571Y271654D02*
X314312Y268528D01*
G01X317420Y271735D02*
X314139Y268589D01*
G01X317255Y271806D02*
X313965Y268649D01*
G01X317092Y271876D02*
X313791Y268710D01*
G01X316929Y271946D02*
X313618Y268770D01*
G01X316765Y272017D02*
X313445Y268832D01*
G01X316602Y272087D02*
X313240Y268863D01*
G01X316428Y272148D02*
X313028Y268886D01*
G01X316250Y272205D02*
X312816Y268910D01*
G01X316072Y272261D02*
X312605Y268935D01*
G01X315894Y272317D02*
X312392Y268958D01*
G01X315716Y272374D02*
X312130Y268934D01*
G01X315531Y272424D02*
X311861Y268903D01*
G01X315338Y272466D02*
X311591Y268872D01*
G01X315144Y272507D02*
X311281Y268801D01*
G01X314951Y272549D02*
X310912Y268675D01*
G01X314758Y272591D02*
X310544Y268548D01*
G01X317571Y271654D02*
X314312Y268528D01*
G01X317420Y271735D02*
X314139Y268589D01*
G01X317255Y271806D02*
X313965Y268649D01*
G01X317092Y271876D02*
X313791Y268710D01*
G01X316929Y271946D02*
X313618Y268770D01*
G01X316765Y272017D02*
X313445Y268832D01*
G01X316602Y272087D02*
X313240Y268863D01*
G01X316428Y272148D02*
X313028Y268886D01*
G01X316250Y272205D02*
X312816Y268910D01*
G01X316072Y272261D02*
X312605Y268935D01*
G01X315894Y272317D02*
X312392Y268958D01*
G01X315716Y272374D02*
X312130Y268934D01*
G01X315531Y272424D02*
X311861Y268903D01*
G01X315338Y272466D02*
X311591Y268872D01*
G01X315144Y272507D02*
X311281Y268801D01*
G01X314951Y272549D02*
X310912Y268675D01*
G01X314758Y272591D02*
X310544Y268548D01*
G01X320866Y561024D02*
G02X309055I-5905J0D01*
G01Y567070D01*
G03X306632Y575463I-15749J0D01*
G02X323289I8329J5246D01*
G03X320866Y567070I13326J-8393D01*
G01Y561024D01*
G01X309055D02*
Y567070D01*
G03X306632Y575463I-15749J0D01*
G02X323289I8329J5246D01*
G03X320866Y567070I13326J-8393D01*
G01Y561024D01*
G02X309055I-5905J0D01*
G01X337000Y-995000D02*
Y-1070000D01*
G01X335000Y-995000D02*
Y-1070000D01*
G01X342507Y-1055000D02*
Y-1050000D01*
X343773D01*
X344280Y-1050250D01*
X344660Y-1050583D01*
X344977Y-1051083D01*
X345230Y-1051667D01*
X345293Y-1052500D01*
X345230Y-1053333D01*
X344977Y-1053917D01*
X344660Y-1054417D01*
X344280Y-1054750D01*
X343773Y-1055000D01*
X342507D01*
G01X347417D02*
X349000Y-1050000D01*
X350583Y-1055000D01*
G01X350013Y-1053250D02*
X347987D01*
G01X354100Y-1050000D02*
Y-1055000D01*
G01X352643Y-1050000D02*
X355557D01*
G01X360467Y-1055000D02*
X357933D01*
Y-1050000D01*
X360467D01*
G01X359453Y-1052417D02*
X357933D01*
G01X364300Y-1055167D02*
X364173Y-1055083D01*
Y-1054917D01*
X364300Y-1054833D01*
X364427Y-1054917D01*
Y-1055083D01*
X364300Y-1055167D01*
G01Y-1052917D02*
X364173Y-1052833D01*
Y-1052667D01*
X364300Y-1052583D01*
X364427Y-1052667D01*
Y-1052833D01*
X364300Y-1052917D01*
G01X337000Y-1045000D02*
X537000D01*
G01X342633Y-1030000D02*
Y-1025000D01*
X344153D01*
X344660Y-1025250D01*
X345040Y-1025833D01*
X345167Y-1026500D01*
X345040Y-1027167D01*
X344723Y-1027667D01*
X344153Y-1027917D01*
X342633D01*
G01X347860Y-1030167D02*
X350140Y-1025000D01*
G01X352643Y-1030000D02*
Y-1025000D01*
X355557Y-1030000D01*
Y-1025000D01*
G01X359200Y-1030167D02*
X359073Y-1030083D01*
Y-1029917D01*
X359200Y-1029833D01*
X359327Y-1029917D01*
Y-1030083D01*
X359200Y-1030167D01*
G01Y-1027917D02*
X359073Y-1027833D01*
Y-1027667D01*
X359200Y-1027583D01*
X359327Y-1027667D01*
Y-1027833D01*
X359200Y-1027917D01*
G01X342633Y-1005000D02*
Y-1000000D01*
X344153D01*
X344660Y-1000250D01*
X345040Y-1000833D01*
X345167Y-1001500D01*
X345040Y-1002167D01*
X344723Y-1002667D01*
X344153Y-1002917D01*
X342633D01*
G01X347733Y-1005000D02*
Y-1000000D01*
X349317D01*
X349823Y-1000250D01*
X350140Y-1000583D01*
X350267Y-1001250D01*
X350140Y-1001917D01*
X349760Y-1002333D01*
X349317Y-1002583D01*
X347733D01*
G01X349317D02*
X350267Y-1005000D01*
G01X354100D02*
X353593Y-1004917D01*
X353150Y-1004583D01*
X352770Y-1004083D01*
X352517Y-1003500D01*
X352390Y-1002833D01*
Y-1002167D01*
X352517Y-1001500D01*
X352770Y-1000917D01*
X353150Y-1000417D01*
X353593Y-1000083D01*
X354100Y-1000000D01*
X354607Y-1000083D01*
X355050Y-1000417D01*
X355430Y-1000917D01*
X355683Y-1001500D01*
X355810Y-1002167D01*
Y-1002833D01*
X355683Y-1003500D01*
X355430Y-1004083D01*
X355050Y-1004583D01*
X354607Y-1004917D01*
X354100Y-1005000D01*
G01X357933Y-1004000D02*
X358250Y-1004500D01*
X358630Y-1004833D01*
X359073Y-1005000D01*
X359580Y-1004833D01*
X359960Y-1004500D01*
X360340Y-1004000D01*
X360467Y-1003333D01*
Y-1000000D01*
G01X365567Y-1005000D02*
X363033D01*
Y-1000000D01*
X365567D01*
G01X364553Y-1002417D02*
X363033D01*
G01X370793Y-1000417D02*
X370413Y-1000167D01*
X369970Y-1000000D01*
X369463D01*
X368893Y-1000250D01*
X368450Y-1000667D01*
X368133Y-1001167D01*
X367880Y-1002000D01*
X367817Y-1002750D01*
X367943Y-1003500D01*
X368133Y-1004000D01*
X368513Y-1004500D01*
X368957Y-1004833D01*
X369400Y-1005000D01*
X369843D01*
X370287Y-1004833D01*
X370667Y-1004583D01*
X370983Y-1004250D01*
G01X374500Y-1000000D02*
Y-1005000D01*
G01X373043Y-1000000D02*
X375957D01*
G01X379600Y-1005167D02*
X379473Y-1005083D01*
Y-1004917D01*
X379600Y-1004833D01*
X379727Y-1004917D01*
Y-1005083D01*
X379600Y-1005167D01*
G01Y-1002917D02*
X379473Y-1002833D01*
Y-1002667D01*
X379600Y-1002583D01*
X379727Y-1002667D01*
Y-1002833D01*
X379600Y-1002917D01*
G01X337000Y-1020000D02*
X537000D01*
G01X346734Y253820D02*
X355697Y262417D01*
G01X346470Y253792D02*
X355744Y262689D01*
G01X346207Y253768D02*
X355793Y262963D01*
G01X345943Y253741D02*
X355841Y263237D01*
G01X345716Y253750D02*
X355888Y263509D01*
G01X345488Y253760D02*
X355937Y263782D01*
G01X355985Y264056D02*
X345267Y253775D01*
G01X345056Y253801D02*
X349614Y258172D01*
G01X344846Y253825D02*
X349093Y257899D01*
G01X344646Y253860D02*
X348711Y257760D01*
G01X344451Y253901D02*
X348337Y257629D01*
G01X344256Y253940D02*
X348066Y257596D01*
G01X344073Y253993D02*
X347795Y257562D01*
G01X343893Y254047D02*
X347524Y257529D01*
G01X343712Y254102D02*
X347263Y257507D01*
G01X343544Y254167D02*
X347043Y257523D01*
G01X343378Y254235D02*
X346823Y257539D01*
G01X343212Y254302D02*
X346613Y257564D01*
G01X343057Y254381D02*
X346426Y257613D01*
G01X342905Y254462D02*
X346240Y257662D01*
G01X342753Y254544D02*
X346069Y257725D01*
G01X342610Y254634D02*
X345916Y257805D01*
G01X342472Y254728D02*
X345763Y257886D01*
G01X342334Y254823D02*
X345636Y257992D01*
G01X342203Y254925D02*
X345516Y258104D01*
G01X342079Y255033D02*
X345406Y258225D01*
G01X341955Y255141D02*
X345320Y258369D01*
G01X341835Y255254D02*
X345233Y258514D01*
G01X341725Y255376D02*
X345180Y258689D01*
G01X341616Y255498D02*
X345128Y258867D01*
G01X341508Y255621D02*
X345106Y259073D01*
G01X341414Y255759D02*
X345091Y259286D01*
G01X341320Y255896D02*
X345111Y259532D01*
G01X341226Y256033D02*
X345147Y259794D01*
G01X341146Y256183D02*
X345272Y260141D01*
G01X346461Y261509D02*
X350280Y265173D01*
G01X341068Y256336D02*
X345398Y260489D01*
G01X340991Y256489D02*
X350080Y265207D01*
G01X340924Y256652D02*
X349880Y265243D01*
G01X340865Y256822D02*
X349679Y265277D01*
G01X340805Y256992D02*
X349467Y265302D01*
G01X340754Y257170D02*
X349242Y265313D01*
G01X340713Y257358D02*
X349018Y265325D01*
G01X337311Y254095D02*
X337430Y254209D01*
G01X337074Y254095D02*
X337479Y254483D01*
G01X340673Y257547D02*
X348793Y265337D01*
G01X336837Y254095D02*
X337526Y254756D01*
G01X340638Y257741D02*
X348569Y265349D01*
G01X340620Y257950D02*
X348321Y265338D01*
G01X336600Y254095D02*
X337574Y255029D01*
G01X340601Y258160D02*
X348068Y265323D01*
G01X336364Y254095D02*
X337622Y255302D01*
G01X336126Y254095D02*
X337671Y255576D01*
G01X340587Y258374D02*
X347815Y265307D01*
G01X340593Y258606D02*
X347561Y265291D01*
G01X335890Y254095D02*
X337719Y255849D01*
G01X340598Y258839D02*
X347308Y265276D01*
G01X335653Y254095D02*
X337766Y256122D01*
G01X335416Y254095D02*
X337814Y256395D01*
G01X340610Y259077D02*
X347044Y265249D01*
G01X340642Y259336D02*
X346746Y265191D01*
G01X335180Y254095D02*
X337862Y256669D01*
G01X340676Y259595D02*
X346448Y265133D01*
G01X334942Y254095D02*
X337911Y256943D01*
G01X334706Y254095D02*
X337959Y257215D01*
G01X340728Y259872D02*
X346151Y265074D01*
G01X340815Y260183D02*
X345853Y265016D01*
G01X334469Y254095D02*
X338006Y257488D01*
G01X334232Y254095D02*
X338054Y257762D01*
G01X340902Y260493D02*
X345498Y264902D01*
G01X340990Y260805D02*
X345123Y264770D01*
G01X333995Y254095D02*
X338103Y258035D01*
G01X341099Y261137D02*
X344749Y264638D01*
G01X333758Y254095D02*
X338151Y258308D01*
G01X333522Y254095D02*
X338199Y258582D01*
G01X341337Y261592D02*
X344298Y264432D01*
G01X333285Y254095D02*
X338246Y258855D01*
G01X333047Y254095D02*
X338294Y259128D01*
G01X333005Y254281D02*
X338343Y259402D01*
G01X333053Y254555D02*
X338391Y259675D01*
G01X333100Y254827D02*
X338439Y259948D01*
G01X333149Y255101D02*
X338486Y260221D01*
G01X332645Y254844D02*
X338535Y260495D01*
G01X332040Y254491D02*
X338583Y260767D01*
G01X331570Y254268D02*
X338631Y261041D01*
G01X331183Y254123D02*
X338679Y261315D01*
G01X330850Y254031D02*
X338726Y261588D01*
G01X330516Y253939D02*
X338775Y261861D01*
G01X330193Y253856D02*
X338823Y262135D01*
G01X329931Y253832D02*
X338871Y262408D01*
G01X329669Y253807D02*
X338919Y262681D01*
G01X329407Y253784D02*
X338967Y262954D01*
G01X329145Y253760D02*
X339015Y263227D01*
G01X328895Y253746D02*
X339063Y263501D01*
G01X328679Y253767D02*
X339111Y263774D01*
G01X328463Y253787D02*
X339159Y264047D01*
G01X328247Y253806D02*
X339207Y264320D01*
G01X339255Y264594D02*
X328031Y253828D01*
G01X333429Y259232D02*
X339303Y264867D01*
G01X327815Y253847D02*
X332497Y258339D01*
G01X333690Y259709D02*
X339351Y265140D01*
G01X327599Y253866D02*
X332036Y258123D01*
G01X327400Y253902D02*
X331712Y258040D01*
G01X333868Y260108D02*
X339399Y265414D01*
G01X327223Y253961D02*
X331400Y257967D01*
G01X333989Y260451D02*
X339447Y265688D01*
G01X339495Y265960D02*
X334101Y260786D01*
G01X327047Y254019D02*
X331145Y257950D01*
G01X326871Y254077D02*
X330891Y257933D01*
G01X339543Y266233D02*
X334166Y261075D01*
G01X326694Y254134D02*
X330652Y257931D01*
G01X339591Y266507D02*
X334232Y261366D01*
G01X326517Y254193D02*
X330430Y257946D01*
G01X339639Y266780D02*
X334297Y261656D01*
G01X326341Y254251D02*
X330209Y257962D01*
G01X326184Y254328D02*
X330008Y257995D01*
G01X326045Y254422D02*
X329822Y258044D01*
G01X325906Y254515D02*
X329636Y258093D01*
G01X325768Y254610D02*
X329473Y258164D01*
G01X325629Y254704D02*
X329325Y258249D01*
G01X325490Y254797D02*
X329176Y258334D01*
G01X322999Y251641D02*
X323007Y251648D01*
G01X325352Y254892D02*
X329052Y258442D01*
G01X322676Y251557D02*
X322871Y251744D01*
G01X322353Y251476D02*
X322734Y251841D01*
G01X325234Y255006D02*
X328943Y258565D01*
G01X325131Y255135D02*
X328835Y258687D01*
G01X322031Y251393D02*
X322597Y251937D01*
G01X325028Y255263D02*
X328744Y258827D01*
G01X321708Y251310D02*
X322461Y252033D01*
G01X321385Y251229D02*
X322324Y252130D01*
G01X324925Y255392D02*
X328674Y258988D01*
G01X324822Y255520D02*
X328604Y259148D01*
G01X321062Y251145D02*
X322188Y252226D01*
G01X320740Y251063D02*
X322052Y252322D01*
G01X324720Y255649D02*
X328541Y259314D01*
G01X324616Y255777D02*
X328508Y259511D01*
G01X320416Y250981D02*
X321916Y252418D01*
G01X320142Y250944D02*
X321779Y252515D01*
G01X324537Y255929D02*
X328475Y259707D01*
G01X319975Y251012D02*
X321643Y252612D01*
G01X324469Y256090D02*
X328443Y259902D01*
G01X324400Y256251D02*
X328435Y260122D01*
G01X319807Y251077D02*
X321507Y252707D01*
G01X324332Y256413D02*
X328437Y260351D01*
G01X319639Y251145D02*
X321371Y252805D01*
G01X319472Y251210D02*
X321234Y252901D01*
G01X324263Y256574D02*
X328439Y260580D01*
G01X324195Y256736D02*
X328441Y260809D01*
G01X319304Y251276D02*
X321098Y252998D01*
G01X319136Y251343D02*
X320962Y253094D01*
G01X324126Y256897D02*
X328475Y261069D01*
G01X318968Y251408D02*
X320825Y253190D01*
G01X324085Y257085D02*
X328508Y261328D01*
G01X324050Y257279D02*
X328542Y261588D01*
G01X318800Y251476D02*
X320689Y253288D01*
G01X324016Y257473D02*
X328576Y261848D01*
G01X318632Y251541D02*
X320553Y253383D01*
G01X318464Y251606D02*
X320417Y253480D01*
G01X323980Y257666D02*
X328624Y262120D01*
G01X323946Y257860D02*
X328672Y262394D01*
G01X318295Y251672D02*
X320281Y253577D01*
G01X318127Y251738D02*
X320144Y253673D01*
G01X323911Y258054D02*
X328719Y262667D01*
G01X323877Y258248D02*
X328768Y262940D01*
G01X317958Y251804D02*
X320008Y253771D01*
G01X323875Y258474D02*
X328816Y263214D01*
G01X317790Y251869D02*
X319872Y253866D01*
G01X317621Y251934D02*
X319736Y253963D01*
G01X323873Y258700D02*
X328864Y263487D01*
G01X323871Y258925D02*
X328911Y263760D01*
G01X317452Y251999D02*
X319600Y254060D01*
G01X317283Y252064D02*
X319464Y254156D01*
G01X323870Y259151D02*
X328959Y264033D01*
G01X323868Y259376D02*
X329008Y264306D01*
G01X317114Y252130D02*
X319328Y254253D01*
G01X316945Y252195D02*
X319192Y254350D01*
G01X323866Y259602D02*
X329055Y264579D01*
G01X316775Y252260D02*
X319055Y254446D01*
G01X329103Y264853D02*
X323874Y259837D01*
G01X329151Y265126D02*
X323906Y260094D01*
G01X329200Y265399D02*
X323937Y260351D01*
G01X329247Y265673D02*
X323968Y260608D01*
G01X329295Y265946D02*
X323999Y260866D01*
G01X329343Y266219D02*
X324031Y261123D01*
G01X329391Y266492D02*
X324062Y261380D01*
G01X329439Y266765D02*
X324105Y261648D01*
G01X322338Y265093D02*
X316792Y259774D01*
G01X322304Y265289D02*
X316972Y260173D01*
G01X322267Y265480D02*
X317152Y260573D01*
G01X322221Y265663D02*
X317240Y260885D01*
G01X322176Y265846D02*
X317316Y261184D01*
G01X322129Y266029D02*
X317392Y261484D01*
G01X321385Y251229D02*
X321708Y251310D01*
G01X322999Y251641D02*
X322676Y251557D01*
G01X321062Y251145D02*
X321385Y251229D01*
G01X320740Y251063D02*
X321062Y251145D01*
G01X322353Y251476D02*
X322676Y251557D01*
G01X321708Y251310D02*
X322031Y251393D01*
G01D02*
X322353Y251476D01*
G01X320416Y250981D02*
X320740Y251063D01*
G01X338486Y260221D02*
X338535Y260495D01*
G01X337074Y254095D02*
X337311D01*
G01X336126D02*
X336364D01*
G01D02*
X336600D01*
G01X335653D02*
X335890D01*
G01D02*
X336126D01*
G01X336837D02*
X337074D01*
G01X336600D02*
X336837D01*
G01X335416D02*
X335653D01*
G01X333285D02*
X333522D01*
G01X335180D02*
X335416D01*
G01X333758D02*
X333995D01*
G01D02*
X334232D01*
G01X333522D02*
X333758D01*
G01X334942D02*
X335180D01*
G01X333047D02*
X333285D01*
G01X334706D02*
X334942D01*
G01X334469D02*
X334706D01*
G01X334232D02*
X334469D01*
G01X333149Y255101D02*
X333100Y254827D01*
G01X333053Y254555D02*
X333005Y254281D01*
G01X333100Y254827D02*
X333053Y254555D01*
G01X333005Y254281D02*
X332973Y254095D01*
X333047D01*
G01X337574Y255029D02*
X337526Y254756D01*
G01D02*
X337479Y254483D01*
G01X337622Y255302D02*
X337574Y255029D01*
G01X337479Y254483D02*
X337430Y254209D01*
G01X337311Y254095D02*
X337410D01*
X337430Y254209D01*
G01X337814Y256395D02*
X337766Y256122D01*
G01D02*
X337719Y255849D01*
G01D02*
X337671Y255576D01*
G01D02*
X337622Y255302D01*
G01X337862Y256669D02*
X337814Y256395D01*
G01X338583Y260767D02*
X338631Y261041D01*
G01X338391Y259675D02*
X338439Y259948D01*
G01D02*
X338486Y260221D01*
G01X338535Y260495D02*
X338583Y260767D01*
G01X338631Y261041D02*
X338679Y261315D01*
G01D02*
X338726Y261588D01*
G01D02*
X338775Y261861D01*
G01X338006Y257488D02*
X337959Y257215D01*
G01X338103Y258035D02*
X338054Y257762D01*
G01D02*
X338006Y257488D01*
G01X337911Y256943D02*
X337862Y256669D01*
G01X337959Y257215D02*
X337911Y256943D01*
G01X338151Y258308D02*
X338103Y258035D01*
G01X338294Y259128D02*
X338246Y258855D01*
G01X338294Y259128D02*
X338343Y259402D01*
G01X338199Y258582D02*
X338151Y258308D01*
G01X338246Y258855D02*
X338199Y258582D01*
G01X338343Y259402D02*
X338391Y259675D01*
G01X324153Y261922D02*
X324105Y261648D01*
G01X346734Y253820D02*
X355697Y262417D01*
G01X346470Y253792D02*
X355744Y262689D01*
G01X346207Y253768D02*
X355793Y262963D01*
G01X345943Y253741D02*
X355841Y263237D01*
G01X345716Y253750D02*
X355888Y263509D01*
G01X345488Y253760D02*
X355937Y263782D01*
G01X355985Y264056D02*
X345267Y253775D01*
G01X345056Y253801D02*
X349614Y258172D01*
G01X344846Y253825D02*
X349093Y257899D01*
G01X344646Y253860D02*
X348711Y257760D01*
G01X344451Y253901D02*
X348337Y257629D01*
G01X344256Y253940D02*
X348066Y257596D01*
G01X344073Y253993D02*
X347795Y257562D01*
G01X343893Y254047D02*
X347524Y257529D01*
G01X343712Y254102D02*
X347263Y257507D01*
G01X343544Y254167D02*
X347043Y257523D01*
G01X343378Y254235D02*
X346823Y257539D01*
G01X343212Y254302D02*
X346613Y257564D01*
G01X343057Y254381D02*
X346426Y257613D01*
G01X342905Y254462D02*
X346240Y257662D01*
G01X342753Y254544D02*
X346069Y257725D01*
G01X342610Y254634D02*
X345916Y257805D01*
G01X342472Y254728D02*
X345763Y257886D01*
G01X342334Y254823D02*
X345636Y257992D01*
G01X342203Y254925D02*
X345516Y258104D01*
G01X342079Y255033D02*
X345406Y258225D01*
G01X341955Y255141D02*
X345320Y258369D01*
G01X341835Y255254D02*
X345233Y258514D01*
G01X341725Y255376D02*
X345180Y258689D01*
G01X341616Y255498D02*
X345128Y258867D01*
G01X341508Y255621D02*
X345106Y259073D01*
G01X341414Y255759D02*
X345091Y259286D01*
G01X341320Y255896D02*
X345111Y259532D01*
G01X341226Y256033D02*
X345147Y259794D01*
G01X341146Y256183D02*
X345272Y260141D01*
G01X346461Y261509D02*
X350280Y265173D01*
G01X341068Y256336D02*
X345398Y260489D01*
G01X340991Y256489D02*
X350080Y265207D01*
G01X340924Y256652D02*
X349880Y265243D01*
G01X340865Y256822D02*
X349679Y265277D01*
G01X340805Y256992D02*
X349467Y265302D01*
G01X340754Y257170D02*
X349242Y265313D01*
G01X340713Y257358D02*
X349018Y265325D01*
G01X337311Y254095D02*
X337430Y254209D01*
G01X337074Y254095D02*
X337479Y254483D01*
G01X340673Y257547D02*
X348793Y265337D01*
G01X336837Y254095D02*
X337526Y254756D01*
G01X340638Y257741D02*
X348569Y265349D01*
G01X340620Y257950D02*
X348321Y265338D01*
G01X336600Y254095D02*
X337574Y255029D01*
G01X340601Y258160D02*
X348068Y265323D01*
G01X336364Y254095D02*
X337622Y255302D01*
G01X336126Y254095D02*
X337671Y255576D01*
G01X340587Y258374D02*
X347815Y265307D01*
G01X340593Y258606D02*
X347561Y265291D01*
G01X335890Y254095D02*
X337719Y255849D01*
G01X340598Y258839D02*
X347308Y265276D01*
G01X335653Y254095D02*
X337766Y256122D01*
G01X335416Y254095D02*
X337814Y256395D01*
G01X340610Y259077D02*
X347044Y265249D01*
G01X340642Y259336D02*
X346746Y265191D01*
G01X335180Y254095D02*
X337862Y256669D01*
G01X340676Y259595D02*
X346448Y265133D01*
G01X334942Y254095D02*
X337911Y256943D01*
G01X334706Y254095D02*
X337959Y257215D01*
G01X340728Y259872D02*
X346151Y265074D01*
G01X340815Y260183D02*
X345853Y265016D01*
G01X334469Y254095D02*
X338006Y257488D01*
G01X334232Y254095D02*
X338054Y257762D01*
G01X340902Y260493D02*
X345498Y264902D01*
G01X340990Y260805D02*
X345123Y264770D01*
G01X333995Y254095D02*
X338103Y258035D01*
G01X341099Y261137D02*
X344749Y264638D01*
G01X333758Y254095D02*
X338151Y258308D01*
G01X333522Y254095D02*
X338199Y258582D01*
G01X341337Y261592D02*
X344298Y264432D01*
G01X333285Y254095D02*
X338246Y258855D01*
G01X333047Y254095D02*
X338294Y259128D01*
G01X333005Y254281D02*
X338343Y259402D01*
G01X333053Y254555D02*
X338391Y259675D01*
G01X333100Y254827D02*
X338439Y259948D01*
G01X333149Y255101D02*
X338486Y260221D01*
G01X332645Y254844D02*
X338535Y260495D01*
G01X332040Y254491D02*
X338583Y260767D01*
G01X331570Y254268D02*
X338631Y261041D01*
G01X331183Y254123D02*
X338679Y261315D01*
G01X330850Y254031D02*
X338726Y261588D01*
G01X330516Y253939D02*
X338775Y261861D01*
G01X330193Y253856D02*
X338823Y262135D01*
G01X329931Y253832D02*
X338871Y262408D01*
G01X329669Y253807D02*
X338919Y262681D01*
G01X329407Y253784D02*
X338967Y262954D01*
G01X329145Y253760D02*
X339015Y263227D01*
G01X328895Y253746D02*
X339063Y263501D01*
G01X328679Y253767D02*
X339111Y263774D01*
G01X328463Y253787D02*
X339159Y264047D01*
G01X328247Y253806D02*
X339207Y264320D01*
G01X339255Y264594D02*
X328031Y253828D01*
G01X333429Y259232D02*
X339303Y264867D01*
G01X327815Y253847D02*
X332497Y258339D01*
G01X333690Y259709D02*
X339351Y265140D01*
G01X327599Y253866D02*
X332036Y258123D01*
G01X327400Y253902D02*
X331712Y258040D01*
G01X333868Y260108D02*
X339399Y265414D01*
G01X327223Y253961D02*
X331400Y257967D01*
G01X333989Y260451D02*
X339447Y265688D01*
G01X339495Y265960D02*
X334101Y260786D01*
G01X327047Y254019D02*
X331145Y257950D01*
G01X326871Y254077D02*
X330891Y257933D01*
G01X339543Y266233D02*
X334166Y261075D01*
G01X326694Y254134D02*
X330652Y257931D01*
G01X339591Y266507D02*
X334232Y261366D01*
G01X326517Y254193D02*
X330430Y257946D01*
G01X339639Y266780D02*
X334297Y261656D01*
G01X326341Y254251D02*
X330209Y257962D01*
G01X326184Y254328D02*
X330008Y257995D01*
G01X326045Y254422D02*
X329822Y258044D01*
G01X325906Y254515D02*
X329636Y258093D01*
G01X325768Y254610D02*
X329473Y258164D01*
G01X325629Y254704D02*
X329325Y258249D01*
G01X325490Y254797D02*
X329176Y258334D01*
G01X322999Y251641D02*
X323007Y251648D01*
G01X325352Y254892D02*
X329052Y258442D01*
G01X322676Y251557D02*
X322871Y251744D01*
G01X322353Y251476D02*
X322734Y251841D01*
G01X325234Y255006D02*
X328943Y258565D01*
G01X325131Y255135D02*
X328835Y258687D01*
G01X322031Y251393D02*
X322597Y251937D01*
G01X325028Y255263D02*
X328744Y258827D01*
G01X321708Y251310D02*
X322461Y252033D01*
G01X321385Y251229D02*
X322324Y252130D01*
G01X324925Y255392D02*
X328674Y258988D01*
G01X324822Y255520D02*
X328604Y259148D01*
G01X321062Y251145D02*
X322188Y252226D01*
G01X320740Y251063D02*
X322052Y252322D01*
G01X324720Y255649D02*
X328541Y259314D01*
G01X324616Y255777D02*
X328508Y259511D01*
G01X320416Y250981D02*
X321916Y252418D01*
G01X320142Y250944D02*
X321779Y252515D01*
G01X324537Y255929D02*
X328475Y259707D01*
G01X319975Y251012D02*
X321643Y252612D01*
G01X324469Y256090D02*
X328443Y259902D01*
G01X324400Y256251D02*
X328435Y260122D01*
G01X319807Y251077D02*
X321507Y252707D01*
G01X324332Y256413D02*
X328437Y260351D01*
G01X319639Y251145D02*
X321371Y252805D01*
G01X319472Y251210D02*
X321234Y252901D01*
G01X324263Y256574D02*
X328439Y260580D01*
G01X324195Y256736D02*
X328441Y260809D01*
G01X319304Y251276D02*
X321098Y252998D01*
G01X319136Y251343D02*
X320962Y253094D01*
G01X324126Y256897D02*
X328475Y261069D01*
G01X318968Y251408D02*
X320825Y253190D01*
G01X324085Y257085D02*
X328508Y261328D01*
G01X324050Y257279D02*
X328542Y261588D01*
G01X318800Y251476D02*
X320689Y253288D01*
G01X324016Y257473D02*
X328576Y261848D01*
G01X318632Y251541D02*
X320553Y253383D01*
G01X318464Y251606D02*
X320417Y253480D01*
G01X323980Y257666D02*
X328624Y262120D01*
G01X323946Y257860D02*
X328672Y262394D01*
G01X318295Y251672D02*
X320281Y253577D01*
G01X318127Y251738D02*
X320144Y253673D01*
G01X323911Y258054D02*
X328719Y262667D01*
G01X323877Y258248D02*
X328768Y262940D01*
G01X317958Y251804D02*
X320008Y253771D01*
G01X323875Y258474D02*
X328816Y263214D01*
G01X317790Y251869D02*
X319872Y253866D01*
G01X317621Y251934D02*
X319736Y253963D01*
G01X323873Y258700D02*
X328864Y263487D01*
G01X323871Y258925D02*
X328911Y263760D01*
G01X317452Y251999D02*
X319600Y254060D01*
G01X317283Y252064D02*
X319464Y254156D01*
G01X323870Y259151D02*
X328959Y264033D01*
G01X323868Y259376D02*
X329008Y264306D01*
G01X317114Y252130D02*
X319328Y254253D01*
G01X316945Y252195D02*
X319192Y254350D01*
G01X323866Y259602D02*
X329055Y264579D01*
G01X316775Y252260D02*
X319055Y254446D01*
G01X329103Y264853D02*
X323874Y259837D01*
G01X329151Y265126D02*
X323906Y260094D01*
G01X329200Y265399D02*
X323937Y260351D01*
G01X329247Y265673D02*
X323968Y260608D01*
G01X329295Y265946D02*
X323999Y260866D01*
G01X329343Y266219D02*
X324031Y261123D01*
G01X329391Y266492D02*
X324062Y261380D01*
G01X329439Y266765D02*
X324105Y261648D01*
G01X322338Y265093D02*
X316792Y259774D01*
G01X322304Y265289D02*
X316972Y260173D01*
G01X322267Y265480D02*
X317152Y260573D01*
G01X322221Y265663D02*
X317240Y260885D01*
G01X322176Y265846D02*
X317316Y261184D01*
G01X322129Y266029D02*
X317392Y261484D01*
G01X321385Y251229D02*
X321708Y251310D01*
G01X322999Y251641D02*
X322676Y251557D01*
G01X321062Y251145D02*
X321385Y251229D01*
G01X320740Y251063D02*
X321062Y251145D01*
G01X322353Y251476D02*
X322676Y251557D01*
G01X321708Y251310D02*
X322031Y251393D01*
G01D02*
X322353Y251476D01*
G01X320416Y250981D02*
X320740Y251063D01*
G01X338486Y260221D02*
X338535Y260495D01*
G01X337074Y254095D02*
X337311D01*
G01X336126D02*
X336364D01*
G01D02*
X336600D01*
G01X335653D02*
X335890D01*
G01D02*
X336126D01*
G01X336837D02*
X337074D01*
G01X336600D02*
X336837D01*
G01X335416D02*
X335653D01*
G01X333285D02*
X333522D01*
G01X335180D02*
X335416D01*
G01X333758D02*
X333995D01*
G01D02*
X334232D01*
G01X333522D02*
X333758D01*
G01X334942D02*
X335180D01*
G01X333047D02*
X333285D01*
G01X334706D02*
X334942D01*
G01X334469D02*
X334706D01*
G01X334232D02*
X334469D01*
G01X333149Y255101D02*
X333100Y254827D01*
G01X333053Y254555D02*
X333005Y254281D01*
G01X333100Y254827D02*
X333053Y254555D01*
G01X333005Y254281D02*
X332973Y254095D01*
X333047D01*
G01X337574Y255029D02*
X337526Y254756D01*
G01D02*
X337479Y254483D01*
G01X337622Y255302D02*
X337574Y255029D01*
G01X337479Y254483D02*
X337430Y254209D01*
G01X337311Y254095D02*
X337410D01*
X337430Y254209D01*
G01X337814Y256395D02*
X337766Y256122D01*
G01D02*
X337719Y255849D01*
G01D02*
X337671Y255576D01*
G01D02*
X337622Y255302D01*
G01X337862Y256669D02*
X337814Y256395D01*
G01X338583Y260767D02*
X338631Y261041D01*
G01X338391Y259675D02*
X338439Y259948D01*
G01D02*
X338486Y260221D01*
G01X338535Y260495D02*
X338583Y260767D01*
G01X338631Y261041D02*
X338679Y261315D01*
G01D02*
X338726Y261588D01*
G01D02*
X338775Y261861D01*
G01X338006Y257488D02*
X337959Y257215D01*
G01X338103Y258035D02*
X338054Y257762D01*
G01D02*
X338006Y257488D01*
G01X337911Y256943D02*
X337862Y256669D01*
G01X337959Y257215D02*
X337911Y256943D01*
G01X338151Y258308D02*
X338103Y258035D01*
G01X338294Y259128D02*
X338246Y258855D01*
G01X338294Y259128D02*
X338343Y259402D01*
G01X338199Y258582D02*
X338151Y258308D01*
G01X338246Y258855D02*
X338199Y258582D01*
G01X338343Y259402D02*
X338391Y259675D01*
G01X324153Y261922D02*
X324105Y261648D01*
G01X341575Y262048D02*
X343746Y264130D01*
G01X350977Y271295D02*
X346816Y267303D01*
G01X350756Y271310D02*
X346460Y267188D01*
G01X350535Y271324D02*
X346081Y267051D01*
G01X350303Y271330D02*
X345659Y266874D01*
G01X350059Y271323D02*
X345203Y266664D01*
G01X349815Y271316D02*
X344913Y266613D01*
G01X349572Y271310D02*
X344850Y266780D01*
G01X349320Y271296D02*
X344787Y266947D01*
G01X349059Y271272D02*
X344724Y267114D01*
G01X348798Y271249D02*
X344662Y267281D01*
G01X348538Y271226D02*
X344599Y267448D01*
G01X348254Y271182D02*
X344536Y267615D01*
G01X347970Y271137D02*
X344473Y267782D01*
G01X347686Y271091D02*
X344410Y267949D01*
G01X347374Y271019D02*
X344347Y268115D01*
G01X347060Y270946D02*
X344285Y268282D01*
G01X346732Y270858D02*
X344222Y268450D01*
G01X339687Y267053D02*
X334350Y261934D01*
G01X339735Y267326D02*
X334398Y262207D01*
G01X339783Y267600D02*
X334446Y262480D01*
G01X339831Y267873D02*
X334494Y262754D01*
G01X339879Y268147D02*
X334542Y263026D01*
G01X339927Y268419D02*
X334590Y263299D01*
G01X339975Y268693D02*
X334638Y263573D01*
G01X340023Y268966D02*
X334686Y263846D01*
G01X340071Y269240D02*
X334733Y264119D01*
G01X340119Y269512D02*
X334781Y264392D01*
G01X340168Y269786D02*
X334829Y264665D01*
G01X340216Y270060D02*
X334877Y264939D01*
G01X340263Y270333D02*
X334925Y265211D01*
G01X340311Y270606D02*
X334973Y265484D01*
G01X340359Y270879D02*
X335021Y265758D01*
G01X340227Y270980D02*
X335068Y266031D01*
G01X339991Y270980D02*
X335117Y266304D01*
G01X339754Y270980D02*
X335164Y266577D01*
G01X339517Y270980D02*
X335212Y266850D01*
G01X339280Y270980D02*
X335260Y267124D01*
G01X339043Y270980D02*
X335308Y267397D01*
G01X338806Y270980D02*
X335356Y267669D01*
G01X338570Y270980D02*
X335403Y267943D01*
G01X338332Y270980D02*
X335452Y268216D01*
G01X338096Y270980D02*
X335499Y268489D01*
G01X329487Y267038D02*
X324153Y261922D01*
G01X329535Y267312D02*
X324201Y262195D01*
G01X329583Y267585D02*
X324249Y262468D01*
G01X329631Y267858D02*
X324297Y262742D01*
G01X329679Y268132D02*
X324345Y263015D01*
G01X329727Y268404D02*
X324393Y263288D01*
G01X329775Y268678D02*
X324441Y263561D01*
G01X329823Y268951D02*
X324489Y263834D01*
G01X329871Y269225D02*
X324536Y264107D01*
G01X329918Y269497D02*
X324585Y264381D01*
G01X329967Y269770D02*
X324633Y264654D01*
G01X330015Y270044D02*
X324680Y264927D01*
G01X330062Y270317D02*
X324728Y265201D01*
G01X330110Y270591D02*
X324777Y265473D01*
G01X330158Y270863D02*
X324825Y265747D01*
G01X330043Y270980D02*
X324872Y266020D01*
G01X329806Y270980D02*
X324920Y266294D01*
G01X329569Y270980D02*
X324968Y266566D01*
G01X329332Y270980D02*
X325016Y266839D01*
G01X329095Y270980D02*
X325064Y267113D01*
G01X328858Y270980D02*
X325112Y267386D01*
G01X328622Y270980D02*
X325160Y267660D01*
G01X328385Y270980D02*
X325208Y267932D01*
G01X328148Y270980D02*
X325256Y268206D01*
G01X327911Y270980D02*
X325304Y268479D01*
G01X322083Y266212D02*
X317455Y261772D01*
G01X322031Y266389D02*
X317475Y262019D01*
G01X321971Y266559D02*
X317495Y262265D01*
G01X321912Y266729D02*
X317515Y262512D01*
G01X321851Y266899D02*
X317535Y262758D01*
G01X321792Y267069D02*
X317539Y262989D01*
G01X321732Y267238D02*
X317521Y263199D01*
G01X321659Y267396D02*
X317504Y263410D01*
G01X321584Y267551D02*
X317486Y263620D01*
G01X321509Y267706D02*
X317468Y263831D01*
G01X321434Y267862D02*
X317451Y264041D01*
G01X321360Y268017D02*
X317420Y264238D01*
G01X321284Y268172D02*
X317372Y264420D01*
G01X321198Y268317D02*
X317325Y264602D01*
G01X321107Y268457D02*
X317278Y264784D01*
G01X321016Y268596D02*
X317230Y264965D01*
G01X320924Y268736D02*
X317183Y265146D01*
G01X320833Y268876D02*
X317133Y265326D01*
G01X320741Y269015D02*
X317060Y265483D01*
G01X320650Y269154D02*
X316988Y265641D01*
G01X320542Y269278D02*
X316915Y265799D01*
G01X320432Y269400D02*
X316842Y265956D01*
G01X320323Y269522D02*
X316769Y266113D01*
G01X320213Y269644D02*
X316697Y266271D01*
G01X344222Y268450D02*
X344285Y268282D01*
G01X344159Y268617D02*
X344222Y268450D01*
G01X344285Y268282D02*
X344347Y268115D01*
G01X344850Y266780D02*
X344913Y266613D01*
G01X344536Y267615D02*
X344599Y267448D01*
G01X344473Y267782D02*
X344536Y267615D01*
G01X344410Y267949D02*
X344473Y267782D01*
G01X344599Y267448D02*
X344662Y267281D01*
G01X344787Y266947D02*
X344850Y266780D01*
G01X344347Y268115D02*
X344410Y267949D01*
G01X344662Y267281D02*
X344724Y267114D01*
G01D02*
X344787Y266947D01*
G01X335117Y266304D02*
X335068Y266031D01*
G01X339351Y265140D02*
X339399Y265414D01*
G01X339303Y264867D02*
X339351Y265140D01*
G01X338871Y262408D02*
X338919Y262681D01*
G01X338967Y262954D02*
X339015Y263227D01*
G01X338919Y262681D02*
X338967Y262954D01*
G01X339255Y264594D02*
X339207Y264320D01*
G01X339063Y263501D02*
X339111Y263774D01*
G01X339207Y264320D02*
X339159Y264047D01*
G01X339111Y263774D02*
X339159Y264047D01*
G01X328768Y262940D02*
X328816Y263214D01*
G01X328624Y262120D02*
X328672Y262394D01*
G01X328816Y263214D02*
X328864Y263487D01*
G01X328576Y261848D02*
X328624Y262120D01*
G01X328719Y262667D02*
X328768Y262940D01*
G01X328959Y264033D02*
X329008Y264306D01*
G01X328911Y263760D02*
X328959Y264033D01*
G01X328864Y263487D02*
X328911Y263760D01*
G01X339015Y263227D02*
X339063Y263501D01*
G01X339255Y264594D02*
X339303Y264867D01*
G01X329055Y264579D02*
X329103Y264853D01*
G01D02*
X329151Y265126D01*
G01X339687Y267053D02*
X339735Y267326D01*
G01X339639Y266780D02*
X339687Y267053D01*
G01X339831Y267873D02*
X339879Y268147D01*
G01X339783Y267600D02*
X339831Y267873D01*
G01X339447Y265688D02*
X339495Y265960D01*
G01X339543Y266233D02*
X339591Y266507D01*
G01D02*
X339639Y266780D01*
G01X339495Y265960D02*
X339543Y266233D01*
G01X339735Y267326D02*
X339783Y267600D01*
G01X339879Y268147D02*
X339927Y268419D01*
G01D02*
X339975Y268693D01*
G01X329439Y266765D02*
X329487Y267038D01*
G01X329151Y265126D02*
X329200Y265399D01*
G01X329535Y267312D02*
X329583Y267585D01*
G01X329391Y266492D02*
X329439Y266765D01*
G01X329487Y267038D02*
X329535Y267312D01*
G01X329343Y266219D02*
X329391Y266492D01*
G01X329200Y265399D02*
X329247Y265673D01*
G01X329295Y265946D02*
X329343Y266219D01*
G01X329583Y267585D02*
X329631Y267858D01*
G01X329247Y265673D02*
X329295Y265946D01*
G01X329727Y268404D02*
X329775Y268678D01*
G01X329631Y267858D02*
X329679Y268132D01*
G01D02*
X329727Y268404D01*
G01X328672Y262394D02*
X328719Y262667D01*
G01X325304Y268479D02*
X325256Y268206D01*
G01X325304Y268479D02*
X325352Y268752D01*
G01X325256Y268206D02*
X325208Y267932D01*
G01X324393Y263288D02*
X324345Y263015D01*
G01X324536Y264107D02*
X324489Y263834D01*
G01D02*
X324441Y263561D01*
G01X324680Y264927D02*
X324633Y264654D01*
G01D02*
X324585Y264381D01*
G01D02*
X324536Y264107D01*
G01X324441Y263561D02*
X324393Y263288D01*
G01X325208Y267932D02*
X325160Y267660D01*
G01X324345Y263015D02*
X324297Y262742D01*
G01D02*
X324249Y262468D01*
G01X325064Y267113D02*
X325016Y266839D01*
G01X324728Y265201D02*
X324680Y264927D01*
G01X325016Y266839D02*
X324968Y266566D01*
G01X325160Y267660D02*
X325112Y267386D01*
G01D02*
X325064Y267113D01*
G01X324968Y266566D02*
X324920Y266294D01*
G01X324777Y265473D02*
X324728Y265201D01*
G01X324825Y265747D02*
X324777Y265473D01*
G01X324920Y266294D02*
X324872Y266020D01*
G01D02*
X324825Y265747D01*
G01X338823Y262135D02*
X338871Y262408D01*
G01X324249Y262468D02*
X324201Y262195D01*
G01X334446Y262480D02*
X334398Y262207D01*
G01X339447Y265688D02*
X339399Y265414D01*
G01X334398Y262207D02*
X334350Y261934D01*
G01X334494Y262754D02*
X334446Y262480D01*
G01X338775Y261861D02*
X338823Y262135D01*
G01X334925Y265211D02*
X334877Y264939D01*
G01X334542Y263026D02*
X334494Y262754D01*
G01X329055Y264579D02*
X329008Y264306D01*
G01X334877Y264939D02*
X334829Y264665D01*
G01X335021Y265758D02*
X334973Y265484D01*
G01X324201Y262195D02*
X324153Y261922D01*
G01X334829Y264665D02*
X334781Y264392D01*
G01X334973Y265484D02*
X334925Y265211D01*
G01X334638Y263573D02*
X334590Y263299D01*
G01D02*
X334542Y263026D01*
G01X334781Y264392D02*
X334733Y264119D01*
G01X334686Y263846D02*
X334638Y263573D01*
G01X334733Y264119D02*
X334686Y263846D01*
G01X335499Y268489D02*
X335547Y268762D01*
G01X335356Y267669D02*
X335308Y267397D01*
G01X335403Y267943D02*
X335356Y267669D01*
G01X335452Y268216D02*
X335499Y268489D01*
G01X335452Y268216D02*
X335403Y267943D01*
G01X335260Y267124D02*
X335212Y266850D01*
G01X335068Y266031D02*
X335021Y265758D01*
G01X335164Y266577D02*
X335117Y266304D01*
G01X335212Y266850D02*
X335164Y266577D01*
G01X335308Y267397D02*
X335260Y267124D01*
G01X341575Y262048D02*
X343746Y264130D01*
G01X350977Y271295D02*
X346816Y267303D01*
G01X350756Y271310D02*
X346460Y267188D01*
G01X350535Y271324D02*
X346081Y267051D01*
G01X350303Y271330D02*
X345659Y266874D01*
G01X350059Y271323D02*
X345203Y266664D01*
G01X349815Y271316D02*
X344913Y266613D01*
G01X349572Y271310D02*
X344850Y266780D01*
G01X349320Y271296D02*
X344787Y266947D01*
G01X349059Y271272D02*
X344724Y267114D01*
G01X348798Y271249D02*
X344662Y267281D01*
G01X348538Y271226D02*
X344599Y267448D01*
G01X348254Y271182D02*
X344536Y267615D01*
G01X347970Y271137D02*
X344473Y267782D01*
G01X347686Y271091D02*
X344410Y267949D01*
G01X347374Y271019D02*
X344347Y268115D01*
G01X347060Y270946D02*
X344285Y268282D01*
G01X346732Y270858D02*
X344222Y268450D01*
G01X339687Y267053D02*
X334350Y261934D01*
G01X339735Y267326D02*
X334398Y262207D01*
G01X339783Y267600D02*
X334446Y262480D01*
G01X339831Y267873D02*
X334494Y262754D01*
G01X339879Y268147D02*
X334542Y263026D01*
G01X339927Y268419D02*
X334590Y263299D01*
G01X339975Y268693D02*
X334638Y263573D01*
G01X340023Y268966D02*
X334686Y263846D01*
G01X340071Y269240D02*
X334733Y264119D01*
G01X340119Y269512D02*
X334781Y264392D01*
G01X340168Y269786D02*
X334829Y264665D01*
G01X340216Y270060D02*
X334877Y264939D01*
G01X340263Y270333D02*
X334925Y265211D01*
G01X340311Y270606D02*
X334973Y265484D01*
G01X340359Y270879D02*
X335021Y265758D01*
G01X340227Y270980D02*
X335068Y266031D01*
G01X339991Y270980D02*
X335117Y266304D01*
G01X339754Y270980D02*
X335164Y266577D01*
G01X339517Y270980D02*
X335212Y266850D01*
G01X339280Y270980D02*
X335260Y267124D01*
G01X339043Y270980D02*
X335308Y267397D01*
G01X338806Y270980D02*
X335356Y267669D01*
G01X338570Y270980D02*
X335403Y267943D01*
G01X338332Y270980D02*
X335452Y268216D01*
G01X338096Y270980D02*
X335499Y268489D01*
G01X329487Y267038D02*
X324153Y261922D01*
G01X329535Y267312D02*
X324201Y262195D01*
G01X329583Y267585D02*
X324249Y262468D01*
G01X329631Y267858D02*
X324297Y262742D01*
G01X329679Y268132D02*
X324345Y263015D01*
G01X329727Y268404D02*
X324393Y263288D01*
G01X329775Y268678D02*
X324441Y263561D01*
G01X329823Y268951D02*
X324489Y263834D01*
G01X329871Y269225D02*
X324536Y264107D01*
G01X329918Y269497D02*
X324585Y264381D01*
G01X329967Y269770D02*
X324633Y264654D01*
G01X330015Y270044D02*
X324680Y264927D01*
G01X330062Y270317D02*
X324728Y265201D01*
G01X330110Y270591D02*
X324777Y265473D01*
G01X330158Y270863D02*
X324825Y265747D01*
G01X330043Y270980D02*
X324872Y266020D01*
G01X329806Y270980D02*
X324920Y266294D01*
G01X329569Y270980D02*
X324968Y266566D01*
G01X329332Y270980D02*
X325016Y266839D01*
G01X329095Y270980D02*
X325064Y267113D01*
G01X328858Y270980D02*
X325112Y267386D01*
G01X328622Y270980D02*
X325160Y267660D01*
G01X328385Y270980D02*
X325208Y267932D01*
G01X328148Y270980D02*
X325256Y268206D01*
G01X327911Y270980D02*
X325304Y268479D01*
G01X322083Y266212D02*
X317455Y261772D01*
G01X322031Y266389D02*
X317475Y262019D01*
G01X321971Y266559D02*
X317495Y262265D01*
G01X321912Y266729D02*
X317515Y262512D01*
G01X321851Y266899D02*
X317535Y262758D01*
G01X321792Y267069D02*
X317539Y262989D01*
G01X321732Y267238D02*
X317521Y263199D01*
G01X321659Y267396D02*
X317504Y263410D01*
G01X321584Y267551D02*
X317486Y263620D01*
G01X321509Y267706D02*
X317468Y263831D01*
G01X321434Y267862D02*
X317451Y264041D01*
G01X321360Y268017D02*
X317420Y264238D01*
G01X321284Y268172D02*
X317372Y264420D01*
G01X321198Y268317D02*
X317325Y264602D01*
G01X321107Y268457D02*
X317278Y264784D01*
G01X321016Y268596D02*
X317230Y264965D01*
G01X320924Y268736D02*
X317183Y265146D01*
G01X320833Y268876D02*
X317133Y265326D01*
G01X320741Y269015D02*
X317060Y265483D01*
G01X320650Y269154D02*
X316988Y265641D01*
G01X320542Y269278D02*
X316915Y265799D01*
G01X320432Y269400D02*
X316842Y265956D01*
G01X320323Y269522D02*
X316769Y266113D01*
G01X320213Y269644D02*
X316697Y266271D01*
G01X344222Y268450D02*
X344285Y268282D01*
G01X344159Y268617D02*
X344222Y268450D01*
G01X344285Y268282D02*
X344347Y268115D01*
G01X344850Y266780D02*
X344913Y266613D01*
G01X344536Y267615D02*
X344599Y267448D01*
G01X344473Y267782D02*
X344536Y267615D01*
G01X344410Y267949D02*
X344473Y267782D01*
G01X344599Y267448D02*
X344662Y267281D01*
G01X344787Y266947D02*
X344850Y266780D01*
G01X344347Y268115D02*
X344410Y267949D01*
G01X344662Y267281D02*
X344724Y267114D01*
G01D02*
X344787Y266947D01*
G01X335117Y266304D02*
X335068Y266031D01*
G01X339351Y265140D02*
X339399Y265414D01*
G01X339303Y264867D02*
X339351Y265140D01*
G01X338871Y262408D02*
X338919Y262681D01*
G01X338967Y262954D02*
X339015Y263227D01*
G01X338919Y262681D02*
X338967Y262954D01*
G01X339255Y264594D02*
X339207Y264320D01*
G01X339063Y263501D02*
X339111Y263774D01*
G01X339207Y264320D02*
X339159Y264047D01*
G01X339111Y263774D02*
X339159Y264047D01*
G01X328768Y262940D02*
X328816Y263214D01*
G01X328624Y262120D02*
X328672Y262394D01*
G01X328816Y263214D02*
X328864Y263487D01*
G01X328576Y261848D02*
X328624Y262120D01*
G01X328719Y262667D02*
X328768Y262940D01*
G01X328959Y264033D02*
X329008Y264306D01*
G01X328911Y263760D02*
X328959Y264033D01*
G01X328864Y263487D02*
X328911Y263760D01*
G01X339015Y263227D02*
X339063Y263501D01*
G01X339255Y264594D02*
X339303Y264867D01*
G01X329055Y264579D02*
X329103Y264853D01*
G01D02*
X329151Y265126D01*
G01X339687Y267053D02*
X339735Y267326D01*
G01X339639Y266780D02*
X339687Y267053D01*
G01X339831Y267873D02*
X339879Y268147D01*
G01X339783Y267600D02*
X339831Y267873D01*
G01X339447Y265688D02*
X339495Y265960D01*
G01X339543Y266233D02*
X339591Y266507D01*
G01D02*
X339639Y266780D01*
G01X339495Y265960D02*
X339543Y266233D01*
G01X339735Y267326D02*
X339783Y267600D01*
G01X339879Y268147D02*
X339927Y268419D01*
G01D02*
X339975Y268693D01*
G01X329439Y266765D02*
X329487Y267038D01*
G01X329151Y265126D02*
X329200Y265399D01*
G01X329535Y267312D02*
X329583Y267585D01*
G01X329391Y266492D02*
X329439Y266765D01*
G01X329487Y267038D02*
X329535Y267312D01*
G01X329343Y266219D02*
X329391Y266492D01*
G01X329200Y265399D02*
X329247Y265673D01*
G01X329295Y265946D02*
X329343Y266219D01*
G01X329583Y267585D02*
X329631Y267858D01*
G01X329247Y265673D02*
X329295Y265946D01*
G01X329727Y268404D02*
X329775Y268678D01*
G01X329631Y267858D02*
X329679Y268132D01*
G01D02*
X329727Y268404D01*
G01X328672Y262394D02*
X328719Y262667D01*
G01X325304Y268479D02*
X325256Y268206D01*
G01X325304Y268479D02*
X325352Y268752D01*
G01X325256Y268206D02*
X325208Y267932D01*
G01X324393Y263288D02*
X324345Y263015D01*
G01X324536Y264107D02*
X324489Y263834D01*
G01D02*
X324441Y263561D01*
G01X324680Y264927D02*
X324633Y264654D01*
G01D02*
X324585Y264381D01*
G01D02*
X324536Y264107D01*
G01X324441Y263561D02*
X324393Y263288D01*
G01X325208Y267932D02*
X325160Y267660D01*
G01X324345Y263015D02*
X324297Y262742D01*
G01D02*
X324249Y262468D01*
G01X325064Y267113D02*
X325016Y266839D01*
G01X324728Y265201D02*
X324680Y264927D01*
G01X325016Y266839D02*
X324968Y266566D01*
G01X325160Y267660D02*
X325112Y267386D01*
G01D02*
X325064Y267113D01*
G01X324968Y266566D02*
X324920Y266294D01*
G01X324777Y265473D02*
X324728Y265201D01*
G01X324825Y265747D02*
X324777Y265473D01*
G01X324920Y266294D02*
X324872Y266020D01*
G01D02*
X324825Y265747D01*
G01X338823Y262135D02*
X338871Y262408D01*
G01X324249Y262468D02*
X324201Y262195D01*
G01X334446Y262480D02*
X334398Y262207D01*
G01X339447Y265688D02*
X339399Y265414D01*
G01X334398Y262207D02*
X334350Y261934D01*
G01X334494Y262754D02*
X334446Y262480D01*
G01X338775Y261861D02*
X338823Y262135D01*
G01X334925Y265211D02*
X334877Y264939D01*
G01X334542Y263026D02*
X334494Y262754D01*
G01X329055Y264579D02*
X329008Y264306D01*
G01X334877Y264939D02*
X334829Y264665D01*
G01X335021Y265758D02*
X334973Y265484D01*
G01X324201Y262195D02*
X324153Y261922D01*
G01X334829Y264665D02*
X334781Y264392D01*
G01X334973Y265484D02*
X334925Y265211D01*
G01X334638Y263573D02*
X334590Y263299D01*
G01D02*
X334542Y263026D01*
G01X334781Y264392D02*
X334733Y264119D01*
G01X334686Y263846D02*
X334638Y263573D01*
G01X334733Y264119D02*
X334686Y263846D01*
G01X335499Y268489D02*
X335547Y268762D01*
G01X335356Y267669D02*
X335308Y267397D01*
G01X335403Y267943D02*
X335356Y267669D01*
G01X335452Y268216D02*
X335499Y268489D01*
G01X335452Y268216D02*
X335403Y267943D01*
G01X335260Y267124D02*
X335212Y266850D01*
G01X335068Y266031D02*
X335021Y265758D01*
G01X335164Y266577D02*
X335117Y266304D01*
G01X335212Y266850D02*
X335164Y266577D01*
G01X335308Y267397D02*
X335260Y267124D01*
G01X346382Y270749D02*
X344159Y268617D01*
G01X346023Y270631D02*
X344096Y268783D01*
G01X345628Y270480D02*
X344033Y268950D01*
G01X345219Y270315D02*
X343970Y269118D01*
G01X344775Y270117D02*
X343908Y269284D01*
G01X344304Y269891D02*
X343845Y269451D01*
G01X343807Y269642D02*
X343782Y269618D01*
G01X337859Y270980D02*
X335547Y268762D01*
G01X337622Y270980D02*
X335595Y269035D01*
G01X337385Y270980D02*
X335643Y269309D01*
G01X337148Y270980D02*
X335691Y269582D01*
G01X336912Y270980D02*
X335738Y269854D01*
G01X336675Y270980D02*
X335787Y270128D01*
G01X336438Y270980D02*
X335835Y270401D01*
G01X336201Y270980D02*
X335882Y270674D01*
G01X335964Y270980D02*
X335930Y270947D01*
G01X327674Y270980D02*
X325352Y268752D01*
G01X327438Y270980D02*
X325400Y269025D01*
G01X327200Y270980D02*
X325448Y269299D01*
G01X326964Y270980D02*
X325496Y269572D01*
G01X326727Y270980D02*
X325544Y269845D01*
G01X326490Y270980D02*
X325592Y270118D01*
G01X326253Y270980D02*
X325640Y270391D01*
G01X326016Y270980D02*
X325688Y270665D01*
G01X325780Y270980D02*
X325735Y270938D01*
G01X343970Y269118D02*
X343908Y269284D01*
G01X343970Y269118D02*
X344033Y268950D01*
G01X343908Y269284D02*
X343845Y269451D01*
G01D02*
X343782Y269618D01*
G01X344033Y268950D02*
X344096Y268783D01*
G01D02*
X344159Y268617D01*
G01X338806Y270980D02*
X338570D01*
G01X339043D02*
X338806D01*
G01X338332D02*
X338096D01*
G01D02*
X337859D01*
G01X339991D02*
X339754D01*
G01X339280D02*
X339043D01*
G01X339754D02*
X339517D01*
G01D02*
X339280D01*
G01X336912D02*
X336675D01*
G01D02*
X336438D01*
G01D02*
X336201D01*
G01D02*
X335964D01*
G01X337622D02*
X337385D01*
G01X337148D02*
X336912D01*
G01X340227D02*
X339991D01*
G01X337385D02*
X337148D01*
G01X337859D02*
X337622D01*
G01X340359Y270879D02*
X340377Y270980D01*
X340227D01*
G01X340168Y269786D02*
X340216Y270060D01*
G01D02*
X340263Y270333D01*
G01D02*
X340311Y270606D01*
G01D02*
X340359Y270879D01*
G01X339975Y268693D02*
X340023Y268966D01*
G01X340119Y269512D02*
X340168Y269786D01*
G01X340071Y269240D02*
X340119Y269512D01*
G01X340023Y268966D02*
X340071Y269240D01*
G01X338570Y270980D02*
X338332D01*
G01X329095D02*
X328858D01*
G01D02*
X328622D01*
G01X328148D02*
X327911D01*
G01X328622D02*
X328385D01*
G01D02*
X328148D01*
G01X330043D02*
X329806D01*
G01D02*
X329569D01*
G01X329332D02*
X329095D01*
G01X329569D02*
X329332D01*
G01X330158Y270863D02*
X330179Y270980D01*
X330043D01*
G01X326253D02*
X326016D01*
G01X327911D02*
X327674D01*
G01X326016D02*
X325780D01*
G01X326490D02*
X326253D01*
G01X327674D02*
X327438D01*
G01D02*
X327200D01*
G01D02*
X326964D01*
G01X326727D02*
X326490D01*
G01X326964D02*
X326727D01*
G01X330110Y270591D02*
X330158Y270863D01*
G01X329967Y269770D02*
X330015Y270044D01*
G01X329918Y269497D02*
X329967Y269770D01*
G01X330062Y270317D02*
X330110Y270591D01*
G01X330015Y270044D02*
X330062Y270317D01*
G01X329823Y268951D02*
X329871Y269225D01*
G01D02*
X329918Y269497D01*
G01X329775Y268678D02*
X329823Y268951D01*
G01X325496Y269572D02*
X325544Y269845D01*
G01X325592Y270118D02*
X325640Y270391D01*
G01X325544Y269845D02*
X325592Y270118D01*
G01X325448Y269299D02*
X325496Y269572D01*
G01X325640Y270391D02*
X325688Y270665D01*
G01X325400Y269025D02*
X325448Y269299D01*
G01X325352Y268752D02*
X325400Y269025D01*
G01X325780Y270980D02*
X325743D01*
X325735Y270938D01*
G01X325688Y270665D02*
X325735Y270938D01*
G01X335882Y270674D02*
X335930Y270947D01*
G01X335787Y270128D02*
X335835Y270401D01*
G01X335964Y270980D02*
X335936D01*
X335930Y270947D01*
G01X335595Y269035D02*
X335643Y269309D01*
G01X335691Y269582D02*
X335738Y269854D01*
G01D02*
X335787Y270128D01*
G01X335643Y269309D02*
X335691Y269582D01*
G01X335547Y268762D02*
X335595Y269035D01*
G01X335835Y270401D02*
X335882Y270674D01*
G01X346382Y270749D02*
X344159Y268617D01*
G01X346023Y270631D02*
X344096Y268783D01*
G01X345628Y270480D02*
X344033Y268950D01*
G01X345219Y270315D02*
X343970Y269118D01*
G01X344775Y270117D02*
X343908Y269284D01*
G01X344304Y269891D02*
X343845Y269451D01*
G01X343807Y269642D02*
X343782Y269618D01*
G01X337859Y270980D02*
X335547Y268762D01*
G01X337622Y270980D02*
X335595Y269035D01*
G01X337385Y270980D02*
X335643Y269309D01*
G01X337148Y270980D02*
X335691Y269582D01*
G01X336912Y270980D02*
X335738Y269854D01*
G01X336675Y270980D02*
X335787Y270128D01*
G01X336438Y270980D02*
X335835Y270401D01*
G01X336201Y270980D02*
X335882Y270674D01*
G01X335964Y270980D02*
X335930Y270947D01*
G01X327674Y270980D02*
X325352Y268752D01*
G01X327438Y270980D02*
X325400Y269025D01*
G01X327200Y270980D02*
X325448Y269299D01*
G01X326964Y270980D02*
X325496Y269572D01*
G01X326727Y270980D02*
X325544Y269845D01*
G01X326490Y270980D02*
X325592Y270118D01*
G01X326253Y270980D02*
X325640Y270391D01*
G01X326016Y270980D02*
X325688Y270665D01*
G01X325780Y270980D02*
X325735Y270938D01*
G01X343970Y269118D02*
X343908Y269284D01*
G01X343970Y269118D02*
X344033Y268950D01*
G01X343908Y269284D02*
X343845Y269451D01*
G01D02*
X343782Y269618D01*
G01X344033Y268950D02*
X344096Y268783D01*
G01D02*
X344159Y268617D01*
G01X338806Y270980D02*
X338570D01*
G01X339043D02*
X338806D01*
G01X338332D02*
X338096D01*
G01D02*
X337859D01*
G01X339991D02*
X339754D01*
G01X339280D02*
X339043D01*
G01X339754D02*
X339517D01*
G01D02*
X339280D01*
G01X336912D02*
X336675D01*
G01D02*
X336438D01*
G01D02*
X336201D01*
G01D02*
X335964D01*
G01X337622D02*
X337385D01*
G01X337148D02*
X336912D01*
G01X340227D02*
X339991D01*
G01X337385D02*
X337148D01*
G01X337859D02*
X337622D01*
G01X340359Y270879D02*
X340377Y270980D01*
X340227D01*
G01X340168Y269786D02*
X340216Y270060D01*
G01D02*
X340263Y270333D01*
G01D02*
X340311Y270606D01*
G01D02*
X340359Y270879D01*
G01X339975Y268693D02*
X340023Y268966D01*
G01X340119Y269512D02*
X340168Y269786D01*
G01X340071Y269240D02*
X340119Y269512D01*
G01X340023Y268966D02*
X340071Y269240D01*
G01X338570Y270980D02*
X338332D01*
G01X329095D02*
X328858D01*
G01D02*
X328622D01*
G01X328148D02*
X327911D01*
G01X328622D02*
X328385D01*
G01D02*
X328148D01*
G01X330043D02*
X329806D01*
G01D02*
X329569D01*
G01X329332D02*
X329095D01*
G01X329569D02*
X329332D01*
G01X330158Y270863D02*
X330179Y270980D01*
X330043D01*
G01X326253D02*
X326016D01*
G01X327911D02*
X327674D01*
G01X326016D02*
X325780D01*
G01X326490D02*
X326253D01*
G01X327674D02*
X327438D01*
G01D02*
X327200D01*
G01D02*
X326964D01*
G01X326727D02*
X326490D01*
G01X326964D02*
X326727D01*
G01X330110Y270591D02*
X330158Y270863D01*
G01X329967Y269770D02*
X330015Y270044D01*
G01X329918Y269497D02*
X329967Y269770D01*
G01X330062Y270317D02*
X330110Y270591D01*
G01X330015Y270044D02*
X330062Y270317D01*
G01X329823Y268951D02*
X329871Y269225D01*
G01D02*
X329918Y269497D01*
G01X329775Y268678D02*
X329823Y268951D01*
G01X325496Y269572D02*
X325544Y269845D01*
G01X325592Y270118D02*
X325640Y270391D01*
G01X325544Y269845D02*
X325592Y270118D01*
G01X325448Y269299D02*
X325496Y269572D01*
G01X325640Y270391D02*
X325688Y270665D01*
G01X325400Y269025D02*
X325448Y269299D01*
G01X325352Y268752D02*
X325400Y269025D01*
G01X325780Y270980D02*
X325743D01*
X325735Y270938D01*
G01X325688Y270665D02*
X325735Y270938D01*
G01X335882Y270674D02*
X335930Y270947D01*
G01X335787Y270128D02*
X335835Y270401D01*
G01X335964Y270980D02*
X335936D01*
X335930Y270947D01*
G01X335595Y269035D02*
X335643Y269309D01*
G01X335691Y269582D02*
X335738Y269854D01*
G01D02*
X335787Y270128D01*
G01X335643Y269309D02*
X335691Y269582D01*
G01X335547Y268762D02*
X335595Y269035D01*
G01X335835Y270401D02*
X335882Y270674D01*
G01X361471Y254095D02*
X361533Y254156D01*
G01X361234Y254095D02*
X361581Y254429D01*
G01X360996Y254095D02*
X361628Y254701D01*
G01X360760Y254095D02*
X361677Y254975D01*
G01X360523Y254095D02*
X361726Y255249D01*
G01X360285Y254095D02*
X361773Y255522D01*
G01X360049Y254095D02*
X361821Y255795D01*
G01X359812Y254095D02*
X361870Y256068D01*
G01X359575Y254095D02*
X361918Y256342D01*
G01X359339Y254095D02*
X361966Y256615D01*
G01X359103Y254095D02*
X362013Y256888D01*
G01X358864Y254095D02*
X362062Y257162D01*
G01X358628Y254095D02*
X362110Y257436D01*
G01X358392Y254095D02*
X362157Y257708D01*
G01X358155Y254095D02*
X362206Y257981D01*
G01X357917Y254095D02*
X362255Y258255D01*
G01X357680Y254095D02*
X362302Y258529D01*
G01X357444Y254095D02*
X362350Y258802D01*
G01X357207Y254095D02*
X362399Y259075D01*
G01X357108Y254226D02*
X362447Y259349D01*
G01X357155Y254500D02*
X362495Y259622D01*
G01X357204Y254773D02*
X362542Y259895D01*
G01X357251Y255046D02*
X362591Y260168D01*
G01X357299Y255320D02*
X362639Y260442D01*
G01X357348Y255594D02*
X362686Y260715D01*
G01X357395Y255866D02*
X362735Y260988D01*
G01X357443Y256139D02*
X362784Y261262D01*
G01X357491Y256413D02*
X362831Y261535D01*
G01X357540Y256686D02*
X362879Y261809D01*
G01X357586Y256959D02*
X362928Y262082D01*
G01X362975Y262355D02*
X357635Y257232D01*
G01X354128Y254095D02*
X354261Y254221D01*
G01X363023Y262628D02*
X357684Y257505D01*
G01X363071Y262902D02*
X357731Y257779D01*
G01X353890Y254095D02*
X354308Y254495D01*
G01X363120Y263175D02*
X357779Y258052D01*
G01X353654Y254095D02*
X354356Y254768D01*
G01X353418Y254095D02*
X354404Y255041D01*
G01X363174Y263455D02*
X357828Y258325D01*
G01X353180Y254095D02*
X354450Y255314D01*
G01X363240Y263745D02*
X357875Y258599D01*
G01X363305Y264034D02*
X357923Y258872D01*
G01X352943Y254095D02*
X354499Y255588D01*
G01X363368Y264322D02*
X357972Y259145D01*
G01X352706Y254095D02*
X354548Y255861D01*
G01X352470Y254095D02*
X354594Y256133D01*
G01X363486Y264662D02*
X358019Y259418D01*
G01X352233Y254095D02*
X354643Y256407D01*
G01X363606Y265005D02*
X358066Y259691D01*
G01X363796Y265414D02*
X358115Y259965D01*
G01X351996Y254095D02*
X354692Y256680D01*
G01X364110Y265943D02*
X358163Y260238D01*
G01X351760Y254095D02*
X354738Y256953D01*
G01X351523Y254095D02*
X354787Y257226D01*
G01X369405Y271250D02*
X358210Y260510D01*
G01X369188Y271270D02*
X358259Y260784D01*
G01X351285Y254095D02*
X354834Y257499D01*
G01X351048Y254095D02*
X354882Y257773D01*
G01X368973Y271289D02*
X358307Y261058D01*
G01X368757Y271310D02*
X358354Y261330D01*
G01X350811Y254095D02*
X354931Y258046D01*
G01X350575Y254095D02*
X354978Y258319D01*
G01X368540Y271329D02*
X358403Y261604D01*
G01X350338Y254095D02*
X355026Y258593D01*
G01X350101Y254095D02*
X355074Y258866D01*
G01X349865Y254095D02*
X355122Y259138D01*
G01X349831Y254290D02*
X355169Y259412D01*
G01X349880Y254564D02*
X355218Y259685D01*
G01X349928Y254838D02*
X355266Y259958D01*
G01X349977Y255111D02*
X355313Y260231D01*
G01X349430Y254814D02*
X355362Y260504D01*
G01X348833Y254469D02*
X355409Y260778D01*
G01X348359Y254241D02*
X355457Y261051D01*
G01X347978Y254103D02*
X355506Y261324D01*
G01X347641Y254007D02*
X355553Y261597D01*
G01X347304Y253912D02*
X355601Y261870D01*
G01X346997Y253844D02*
X355649Y262143D01*
G01X356032Y264329D02*
X350699Y259212D01*
G01X356081Y264602D02*
X350746Y259485D01*
G01X356128Y264875D02*
X350794Y259758D01*
G01X356176Y265148D02*
X350842Y260032D01*
G01X356223Y265422D02*
X350890Y260305D01*
G01X356244Y265668D02*
X350938Y260578D01*
G01X356264Y265914D02*
X350986Y260851D01*
G01X356284Y266161D02*
X351034Y261125D01*
G01X356303Y266407D02*
X350924Y261247D01*
G01X356324Y266653D02*
X350784Y261338D01*
G01X356317Y266874D02*
X350632Y261420D01*
G01X356290Y267075D02*
X350476Y261499D01*
G01X356263Y267276D02*
X350312Y261568D01*
G01X356235Y267477D02*
X350140Y261630D01*
G01X356207Y267677D02*
X349961Y261685D01*
G01X361726Y255249D02*
X361677Y254975D01*
G01X361966Y256615D02*
X362013Y256888D01*
G01X361821Y255795D02*
X361773Y255522D01*
G01X361677Y254975D02*
X361628Y254701D01*
G01X361773Y255522D02*
X361726Y255249D01*
G01X362206Y257981D02*
X362255Y258255D01*
G01X361918Y256342D02*
X361870Y256068D01*
G01X362157Y257708D02*
X362206Y257981D01*
G01X362350Y258802D02*
X362399Y259075D01*
G01X362302Y258529D02*
X362350Y258802D01*
G01X362255Y258255D02*
X362302Y258529D01*
G01X362013Y256888D02*
X362062Y257162D01*
G01X361966Y256615D02*
X361918Y256342D01*
G01X362110Y257436D02*
X362157Y257708D01*
G01X362062Y257162D02*
X362110Y257436D01*
G01X362639Y260442D02*
X362686Y260715D01*
G01X361870Y256068D02*
X361821Y255795D01*
G01X362686Y260715D02*
X362735Y260988D01*
G01X362784Y261262D02*
X362831Y261535D01*
G01X362735Y260988D02*
X362784Y261262D01*
G01X362542Y259895D02*
X362591Y260168D01*
G01X362447Y259349D02*
X362495Y259622D01*
G01X362399Y259075D02*
X362447Y259349D01*
G01X362591Y260168D02*
X362639Y260442D01*
G01X362495Y259622D02*
X362542Y259895D01*
G01X362831Y261535D02*
X362879Y261809D01*
G01X357540Y256686D02*
X357491Y256413D01*
G01X357586Y256959D02*
X357540Y256686D01*
G01X357635Y257232D02*
X357586Y256959D01*
G01X357635Y257232D02*
X357684Y257505D01*
G01X357491Y256413D02*
X357443Y256139D01*
G01D02*
X357395Y255866D01*
G01X361234Y254095D02*
X361471D01*
G01X360760D02*
X360996D01*
G01D02*
X361234D01*
G01X360523D02*
X360760D01*
G01X360285D02*
X360523D01*
G01X357204Y254773D02*
X357155Y254500D01*
G01X357444Y254095D02*
X357680D01*
G01X360049D02*
X360285D01*
G01X357108Y254226D02*
X357084Y254095D01*
X357207D01*
G01X357155Y254500D02*
X357108Y254226D01*
G01X357395Y255866D02*
X357348Y255594D01*
G01D02*
X357299Y255320D01*
G01D02*
X357251Y255046D01*
G01D02*
X357204Y254773D01*
G01X357207Y254095D02*
X357444D01*
G01X359339D02*
X359575D01*
G01X359812D02*
X360049D01*
G01X359103D02*
X359339D01*
G01X359575D02*
X359812D01*
G01X358392D02*
X358628D01*
G01X358155D02*
X358392D01*
G01X357917D02*
X358155D01*
G01X358864D02*
X359103D01*
G01X358628D02*
X358864D01*
G01X357680D02*
X357917D01*
G01X358066Y259691D02*
X358019Y259418D01*
G01X357923Y258872D02*
X357875Y258599D01*
G01X357828Y258325D02*
X357779Y258052D01*
G01X358019Y259418D02*
X357972Y259145D01*
G01D02*
X357923Y258872D01*
G01X357875Y258599D02*
X357828Y258325D01*
G01X357779Y258052D02*
X357731Y257779D01*
G01D02*
X357684Y257505D01*
G01X358115Y259965D02*
X358066Y259691D01*
G01X358210Y260510D02*
X358163Y260238D01*
G01D02*
X358115Y259965D01*
G01X358307Y261058D02*
X358259Y260784D01*
G01X358403Y261604D02*
X358354Y261330D01*
G01D02*
X358307Y261058D01*
G01X358259Y260784D02*
X358210Y260510D01*
G01X361581Y254429D02*
X361533Y254156D01*
G01X361628Y254701D02*
X361581Y254429D01*
G01X361471Y254095D02*
X361522D01*
X361533Y254156D01*
G01X358450Y261877D02*
X358403Y261604D01*
G01X350746Y259485D02*
X350699Y259212D01*
G01X350986Y260851D02*
X350938Y260578D01*
G01X351034Y261125D02*
X350986Y260851D01*
G01X355313Y260231D02*
X355362Y260504D01*
G01X350890Y260305D02*
X350842Y260032D01*
G01D02*
X350794Y259758D01*
G01X350938Y260578D02*
X350890Y260305D01*
G01X350794Y259758D02*
X350746Y259485D01*
G01X355122Y259138D02*
X355169Y259412D01*
G01X351996Y254095D02*
X352233D01*
G01X352470D02*
X352706D01*
G01D02*
X352943D01*
G01X352233D02*
X352470D01*
G01X353654D02*
X353890D01*
G01D02*
X354128D01*
G01X353180D02*
X353418D01*
G01D02*
X353654D01*
G01X351760D02*
X351996D01*
G01X352943D02*
X353180D01*
G01X351523D02*
X351760D01*
G01X350338D02*
X350575D01*
G01X350101D02*
X350338D01*
G01X349831Y254290D02*
X349797Y254095D01*
X349865D01*
G01D02*
X350101D01*
G01X349880Y254564D02*
X349831Y254290D01*
G01X351285Y254095D02*
X351523D01*
G01X350811D02*
X351048D01*
G01X350575D02*
X350811D01*
G01X351048D02*
X351285D01*
G01X349977Y255111D02*
X349928Y254838D01*
G01D02*
X349880Y254564D01*
G01X354931Y258046D02*
X354978Y258319D01*
G01X355218Y259685D02*
X355266Y259958D01*
G01D02*
X355313Y260231D01*
G01X355074Y258866D02*
X355122Y259138D01*
G01X355169Y259412D02*
X355218Y259685D01*
G01X355409Y260778D02*
X355457Y261051D01*
G01X355362Y260504D02*
X355409Y260778D01*
G01X354738Y256953D02*
X354787Y257226D01*
G01X354548Y255861D02*
X354594Y256133D01*
G01X354692Y256680D02*
X354738Y256953D01*
G01X354643Y256407D02*
X354692Y256680D01*
G01X354594Y256133D02*
X354643Y256407D01*
G01X354882Y257773D02*
X354931Y258046D01*
G01X354978Y258319D02*
X355026Y258593D01*
G01D02*
X355074Y258866D01*
G01X354834Y257499D02*
X354882Y257773D01*
G01X354787Y257226D02*
X354834Y257499D01*
G01X355506Y261324D02*
X355553Y261597D01*
G01D02*
X355601Y261870D01*
G01X355457Y261051D02*
X355506Y261324D01*
G01X354499Y255588D02*
X354548Y255861D01*
G01X354128Y254095D02*
X354238D01*
X354261Y254221D01*
G01D02*
X354308Y254495D01*
G01X354404Y255041D02*
X354450Y255314D01*
G01D02*
X354499Y255588D01*
G01X354308Y254495D02*
X354356Y254768D01*
G01D02*
X354404Y255041D01*
G01X361471Y254095D02*
X361533Y254156D01*
G01X361234Y254095D02*
X361581Y254429D01*
G01X360996Y254095D02*
X361628Y254701D01*
G01X360760Y254095D02*
X361677Y254975D01*
G01X360523Y254095D02*
X361726Y255249D01*
G01X360285Y254095D02*
X361773Y255522D01*
G01X360049Y254095D02*
X361821Y255795D01*
G01X359812Y254095D02*
X361870Y256068D01*
G01X359575Y254095D02*
X361918Y256342D01*
G01X359339Y254095D02*
X361966Y256615D01*
G01X359103Y254095D02*
X362013Y256888D01*
G01X358864Y254095D02*
X362062Y257162D01*
G01X358628Y254095D02*
X362110Y257436D01*
G01X358392Y254095D02*
X362157Y257708D01*
G01X358155Y254095D02*
X362206Y257981D01*
G01X357917Y254095D02*
X362255Y258255D01*
G01X357680Y254095D02*
X362302Y258529D01*
G01X357444Y254095D02*
X362350Y258802D01*
G01X357207Y254095D02*
X362399Y259075D01*
G01X357108Y254226D02*
X362447Y259349D01*
G01X357155Y254500D02*
X362495Y259622D01*
G01X357204Y254773D02*
X362542Y259895D01*
G01X357251Y255046D02*
X362591Y260168D01*
G01X357299Y255320D02*
X362639Y260442D01*
G01X357348Y255594D02*
X362686Y260715D01*
G01X357395Y255866D02*
X362735Y260988D01*
G01X357443Y256139D02*
X362784Y261262D01*
G01X357491Y256413D02*
X362831Y261535D01*
G01X357540Y256686D02*
X362879Y261809D01*
G01X357586Y256959D02*
X362928Y262082D01*
G01X362975Y262355D02*
X357635Y257232D01*
G01X354128Y254095D02*
X354261Y254221D01*
G01X363023Y262628D02*
X357684Y257505D01*
G01X363071Y262902D02*
X357731Y257779D01*
G01X353890Y254095D02*
X354308Y254495D01*
G01X363120Y263175D02*
X357779Y258052D01*
G01X353654Y254095D02*
X354356Y254768D01*
G01X353418Y254095D02*
X354404Y255041D01*
G01X363174Y263455D02*
X357828Y258325D01*
G01X353180Y254095D02*
X354450Y255314D01*
G01X363240Y263745D02*
X357875Y258599D01*
G01X363305Y264034D02*
X357923Y258872D01*
G01X352943Y254095D02*
X354499Y255588D01*
G01X363368Y264322D02*
X357972Y259145D01*
G01X352706Y254095D02*
X354548Y255861D01*
G01X352470Y254095D02*
X354594Y256133D01*
G01X363486Y264662D02*
X358019Y259418D01*
G01X352233Y254095D02*
X354643Y256407D01*
G01X363606Y265005D02*
X358066Y259691D01*
G01X363796Y265414D02*
X358115Y259965D01*
G01X351996Y254095D02*
X354692Y256680D01*
G01X364110Y265943D02*
X358163Y260238D01*
G01X351760Y254095D02*
X354738Y256953D01*
G01X351523Y254095D02*
X354787Y257226D01*
G01X369405Y271250D02*
X358210Y260510D01*
G01X369188Y271270D02*
X358259Y260784D01*
G01X351285Y254095D02*
X354834Y257499D01*
G01X351048Y254095D02*
X354882Y257773D01*
G01X368973Y271289D02*
X358307Y261058D01*
G01X368757Y271310D02*
X358354Y261330D01*
G01X350811Y254095D02*
X354931Y258046D01*
G01X350575Y254095D02*
X354978Y258319D01*
G01X368540Y271329D02*
X358403Y261604D01*
G01X350338Y254095D02*
X355026Y258593D01*
G01X350101Y254095D02*
X355074Y258866D01*
G01X349865Y254095D02*
X355122Y259138D01*
G01X349831Y254290D02*
X355169Y259412D01*
G01X349880Y254564D02*
X355218Y259685D01*
G01X349928Y254838D02*
X355266Y259958D01*
G01X349977Y255111D02*
X355313Y260231D01*
G01X349430Y254814D02*
X355362Y260504D01*
G01X348833Y254469D02*
X355409Y260778D01*
G01X348359Y254241D02*
X355457Y261051D01*
G01X347978Y254103D02*
X355506Y261324D01*
G01X347641Y254007D02*
X355553Y261597D01*
G01X347304Y253912D02*
X355601Y261870D01*
G01X346997Y253844D02*
X355649Y262143D01*
G01X356032Y264329D02*
X350699Y259212D01*
G01X356081Y264602D02*
X350746Y259485D01*
G01X356128Y264875D02*
X350794Y259758D01*
G01X356176Y265148D02*
X350842Y260032D01*
G01X356223Y265422D02*
X350890Y260305D01*
G01X356244Y265668D02*
X350938Y260578D01*
G01X356264Y265914D02*
X350986Y260851D01*
G01X356284Y266161D02*
X351034Y261125D01*
G01X356303Y266407D02*
X350924Y261247D01*
G01X356324Y266653D02*
X350784Y261338D01*
G01X356317Y266874D02*
X350632Y261420D01*
G01X356290Y267075D02*
X350476Y261499D01*
G01X356263Y267276D02*
X350312Y261568D01*
G01X356235Y267477D02*
X350140Y261630D01*
G01X356207Y267677D02*
X349961Y261685D01*
G01X361726Y255249D02*
X361677Y254975D01*
G01X361966Y256615D02*
X362013Y256888D01*
G01X361821Y255795D02*
X361773Y255522D01*
G01X361677Y254975D02*
X361628Y254701D01*
G01X361773Y255522D02*
X361726Y255249D01*
G01X362206Y257981D02*
X362255Y258255D01*
G01X361918Y256342D02*
X361870Y256068D01*
G01X362157Y257708D02*
X362206Y257981D01*
G01X362350Y258802D02*
X362399Y259075D01*
G01X362302Y258529D02*
X362350Y258802D01*
G01X362255Y258255D02*
X362302Y258529D01*
G01X362013Y256888D02*
X362062Y257162D01*
G01X361966Y256615D02*
X361918Y256342D01*
G01X362110Y257436D02*
X362157Y257708D01*
G01X362062Y257162D02*
X362110Y257436D01*
G01X362639Y260442D02*
X362686Y260715D01*
G01X361870Y256068D02*
X361821Y255795D01*
G01X362686Y260715D02*
X362735Y260988D01*
G01X362784Y261262D02*
X362831Y261535D01*
G01X362735Y260988D02*
X362784Y261262D01*
G01X362542Y259895D02*
X362591Y260168D01*
G01X362447Y259349D02*
X362495Y259622D01*
G01X362399Y259075D02*
X362447Y259349D01*
G01X362591Y260168D02*
X362639Y260442D01*
G01X362495Y259622D02*
X362542Y259895D01*
G01X362831Y261535D02*
X362879Y261809D01*
G01X357540Y256686D02*
X357491Y256413D01*
G01X357586Y256959D02*
X357540Y256686D01*
G01X357635Y257232D02*
X357586Y256959D01*
G01X357635Y257232D02*
X357684Y257505D01*
G01X357491Y256413D02*
X357443Y256139D01*
G01D02*
X357395Y255866D01*
G01X361234Y254095D02*
X361471D01*
G01X360760D02*
X360996D01*
G01D02*
X361234D01*
G01X360523D02*
X360760D01*
G01X360285D02*
X360523D01*
G01X357204Y254773D02*
X357155Y254500D01*
G01X357444Y254095D02*
X357680D01*
G01X360049D02*
X360285D01*
G01X357108Y254226D02*
X357084Y254095D01*
X357207D01*
G01X357155Y254500D02*
X357108Y254226D01*
G01X357395Y255866D02*
X357348Y255594D01*
G01D02*
X357299Y255320D01*
G01D02*
X357251Y255046D01*
G01D02*
X357204Y254773D01*
G01X357207Y254095D02*
X357444D01*
G01X359339D02*
X359575D01*
G01X359812D02*
X360049D01*
G01X359103D02*
X359339D01*
G01X359575D02*
X359812D01*
G01X358392D02*
X358628D01*
G01X358155D02*
X358392D01*
G01X357917D02*
X358155D01*
G01X358864D02*
X359103D01*
G01X358628D02*
X358864D01*
G01X357680D02*
X357917D01*
G01X358066Y259691D02*
X358019Y259418D01*
G01X357923Y258872D02*
X357875Y258599D01*
G01X357828Y258325D02*
X357779Y258052D01*
G01X358019Y259418D02*
X357972Y259145D01*
G01D02*
X357923Y258872D01*
G01X357875Y258599D02*
X357828Y258325D01*
G01X357779Y258052D02*
X357731Y257779D01*
G01D02*
X357684Y257505D01*
G01X358115Y259965D02*
X358066Y259691D01*
G01X358210Y260510D02*
X358163Y260238D01*
G01D02*
X358115Y259965D01*
G01X358307Y261058D02*
X358259Y260784D01*
G01X358403Y261604D02*
X358354Y261330D01*
G01D02*
X358307Y261058D01*
G01X358259Y260784D02*
X358210Y260510D01*
G01X361581Y254429D02*
X361533Y254156D01*
G01X361628Y254701D02*
X361581Y254429D01*
G01X361471Y254095D02*
X361522D01*
X361533Y254156D01*
G01X358450Y261877D02*
X358403Y261604D01*
G01X350746Y259485D02*
X350699Y259212D01*
G01X350986Y260851D02*
X350938Y260578D01*
G01X351034Y261125D02*
X350986Y260851D01*
G01X355313Y260231D02*
X355362Y260504D01*
G01X350890Y260305D02*
X350842Y260032D01*
G01D02*
X350794Y259758D01*
G01X350938Y260578D02*
X350890Y260305D01*
G01X350794Y259758D02*
X350746Y259485D01*
G01X355122Y259138D02*
X355169Y259412D01*
G01X351996Y254095D02*
X352233D01*
G01X352470D02*
X352706D01*
G01D02*
X352943D01*
G01X352233D02*
X352470D01*
G01X353654D02*
X353890D01*
G01D02*
X354128D01*
G01X353180D02*
X353418D01*
G01D02*
X353654D01*
G01X351760D02*
X351996D01*
G01X352943D02*
X353180D01*
G01X351523D02*
X351760D01*
G01X350338D02*
X350575D01*
G01X350101D02*
X350338D01*
G01X349831Y254290D02*
X349797Y254095D01*
X349865D01*
G01D02*
X350101D01*
G01X349880Y254564D02*
X349831Y254290D01*
G01X351285Y254095D02*
X351523D01*
G01X350811D02*
X351048D01*
G01X350575D02*
X350811D01*
G01X351048D02*
X351285D01*
G01X349977Y255111D02*
X349928Y254838D01*
G01D02*
X349880Y254564D01*
G01X354931Y258046D02*
X354978Y258319D01*
G01X355218Y259685D02*
X355266Y259958D01*
G01D02*
X355313Y260231D01*
G01X355074Y258866D02*
X355122Y259138D01*
G01X355169Y259412D02*
X355218Y259685D01*
G01X355409Y260778D02*
X355457Y261051D01*
G01X355362Y260504D02*
X355409Y260778D01*
G01X354738Y256953D02*
X354787Y257226D01*
G01X354548Y255861D02*
X354594Y256133D01*
G01X354692Y256680D02*
X354738Y256953D01*
G01X354643Y256407D02*
X354692Y256680D01*
G01X354594Y256133D02*
X354643Y256407D01*
G01X354882Y257773D02*
X354931Y258046D01*
G01X354978Y258319D02*
X355026Y258593D01*
G01D02*
X355074Y258866D01*
G01X354834Y257499D02*
X354882Y257773D01*
G01X354787Y257226D02*
X354834Y257499D01*
G01X355506Y261324D02*
X355553Y261597D01*
G01D02*
X355601Y261870D01*
G01X355457Y261051D02*
X355506Y261324D01*
G01X354499Y255588D02*
X354548Y255861D01*
G01X354128Y254095D02*
X354238D01*
X354261Y254221D01*
G01D02*
X354308Y254495D01*
G01X354404Y255041D02*
X354450Y255314D01*
G01D02*
X354499Y255588D01*
G01X354308Y254495D02*
X354356Y254768D01*
G01D02*
X354404Y255041D01*
G01X369837Y271210D02*
X365381Y266935D01*
G01X369621Y271230D02*
X364919Y266719D01*
G01X368286Y271312D02*
X358450Y261877D01*
G01X368025Y271289D02*
X358498Y262150D01*
G01X367762Y271264D02*
X358547Y262423D01*
G01X367501Y271240D02*
X358594Y262696D01*
G01X367238Y271216D02*
X358642Y262970D01*
G01X366907Y271126D02*
X358690Y263243D01*
G01X366575Y271034D02*
X358738Y263516D01*
G01X366242Y270941D02*
X358785Y263789D01*
G01X365841Y270784D02*
X358834Y264063D01*
G01X365370Y270561D02*
X358882Y264336D01*
G01X364721Y270164D02*
X358929Y264609D01*
G01X364314Y270001D02*
X358978Y264882D01*
G01X364363Y270275D02*
X359027Y265156D01*
G01X364410Y270548D02*
X359073Y265429D01*
G01X364458Y270821D02*
X359122Y265702D01*
G01X364387Y270980D02*
X359171Y265975D01*
G01X364150Y270980D02*
X359217Y266248D01*
G01X363912Y270980D02*
X359265Y266522D01*
G01X363676Y270980D02*
X359314Y266795D01*
G01X363440Y270980D02*
X359362Y267068D01*
G01X363203Y270980D02*
X359409Y267341D01*
G01X362966Y270980D02*
X359458Y267615D01*
G01X362730Y270980D02*
X359506Y267888D01*
G01X362492Y270980D02*
X359553Y268161D01*
G01X362255Y270980D02*
X359602Y268434D01*
G01X356180Y267878D02*
X349771Y261731D01*
G01X356124Y268054D02*
X349576Y261772D01*
G01X356059Y268216D02*
X349372Y261802D01*
G01X355991Y268379D02*
X349163Y261829D01*
G01X355923Y268542D02*
X348945Y261847D01*
G01X355857Y268705D02*
X348723Y261862D01*
G01X351498Y264750D02*
X348496Y261871D01*
G01X355791Y268868D02*
X351703Y264947D01*
G01X351339Y264825D02*
X348264Y261876D01*
G01X355708Y269016D02*
X351750Y265220D01*
G01X355606Y269146D02*
X351797Y265493D01*
G01X351180Y264899D02*
X348024Y261872D01*
G01X351009Y264964D02*
X347752Y261838D01*
G01X355506Y269276D02*
X351823Y265744D01*
G01X355404Y269406D02*
X351837Y265985D01*
G01X347479Y261804D02*
X350831Y265020D01*
G01X347207Y261770D02*
X350653Y265076D01*
G01X355302Y269536D02*
X351816Y266191D01*
G01X346926Y261728D02*
X350474Y265132D01*
G01X355202Y269666D02*
X351786Y266390D01*
G01X355099Y269797D02*
X351728Y266562D01*
G01X354967Y269896D02*
X351667Y266730D01*
G01X354836Y269997D02*
X351576Y266870D01*
G01X354703Y270097D02*
X351484Y267009D01*
G01X354570Y270197D02*
X351368Y267125D01*
G01X354437Y270297D02*
X351245Y267234D01*
G01X354305Y270397D02*
X351110Y267332D01*
G01X354163Y270487D02*
X350957Y267412D01*
G01X354000Y270559D02*
X350803Y267492D01*
G01X353837Y270631D02*
X350620Y267544D01*
G01X353676Y270703D02*
X350435Y267593D01*
G01X353514Y270774D02*
X350236Y267630D01*
G01X353352Y270846D02*
X350017Y267647D01*
G01X353190Y270918D02*
X349798Y267664D01*
G01X353009Y270971D02*
X349560Y267662D01*
G01X352817Y271015D02*
X349317Y267658D01*
G01X352626Y271059D02*
X349075Y267653D01*
G01X352435Y271103D02*
X348822Y267637D01*
G01X352244Y271147D02*
X348568Y267620D01*
G01X352052Y271190D02*
X348306Y267597D01*
G01X351861Y271234D02*
X348033Y267561D01*
G01X351640Y271249D02*
X347756Y267523D01*
G01X351420Y271264D02*
X347457Y267463D01*
G01X351198Y271279D02*
X347149Y267395D01*
G01X362928Y262082D02*
X362879Y261809D01*
G01X362975Y262355D02*
X362928Y262082D01*
G01X363023Y262628D02*
X362975Y262355D01*
G01X363071Y262902D02*
X363023Y262628D01*
G01X358978Y264882D02*
X358929Y264609D01*
G01X363120Y263175D02*
X363071Y262902D01*
G01X358929Y264609D02*
X358882Y264336D01*
G01X359458Y267615D02*
X359506Y267888D01*
G01D02*
X359553Y268161D01*
G01X359602Y268434D02*
X359649Y268707D01*
G01X359362Y267068D02*
X359314Y266795D01*
G01D02*
X359265Y266522D01*
G01X359409Y267341D02*
X359458Y267615D01*
G01X359362Y267068D02*
X359409Y267341D01*
G01X359553Y268161D02*
X359602Y268434D01*
G01X359265Y266522D02*
X359217Y266248D01*
G01X358642Y262970D02*
X358594Y262696D01*
G01X358690Y263243D02*
X358642Y262970D01*
G01X358594Y262696D02*
X358547Y262423D01*
G01X359217Y266248D02*
X359171Y265975D01*
G01X358547Y262423D02*
X358498Y262150D01*
G01D02*
X358450Y261877D01*
G01X359027Y265156D02*
X358978Y264882D01*
G01X359073Y265429D02*
X359027Y265156D01*
G01X359122Y265702D02*
X359073Y265429D01*
G01X359171Y265975D02*
X359122Y265702D01*
G01X358882Y264336D02*
X358834Y264063D01*
G01X358785Y263789D02*
X358738Y263516D01*
G01X358834Y264063D02*
X358785Y263789D01*
G01X358738Y263516D02*
X358690Y263243D01*
G01X355985Y264056D02*
X355937Y263782D01*
G01X356128Y264875D02*
X356081Y264602D01*
G01X356176Y265148D02*
X356128Y264875D01*
G01X356032Y264329D02*
X355985Y264056D01*
G01X356081Y264602D02*
X356032Y264329D01*
G01X355793Y262963D02*
X355841Y263237D01*
G01X355744Y262689D02*
X355793Y262963D01*
G01X355841Y263237D02*
X355888Y263509D01*
G01X355937Y263782D02*
X355888Y263509D01*
G01X355649Y262143D02*
X355697Y262417D01*
G01X355601Y261870D02*
X355649Y262143D01*
G01X355697Y262417D02*
X355744Y262689D01*
G01X351750Y265220D02*
X351703Y264947D01*
G01X351797Y265493D02*
X351750Y265220D01*
G01X369837Y271210D02*
X365381Y266935D01*
G01X369621Y271230D02*
X364919Y266719D01*
G01X368286Y271312D02*
X358450Y261877D01*
G01X368025Y271289D02*
X358498Y262150D01*
G01X367762Y271264D02*
X358547Y262423D01*
G01X367501Y271240D02*
X358594Y262696D01*
G01X367238Y271216D02*
X358642Y262970D01*
G01X366907Y271126D02*
X358690Y263243D01*
G01X366575Y271034D02*
X358738Y263516D01*
G01X366242Y270941D02*
X358785Y263789D01*
G01X365841Y270784D02*
X358834Y264063D01*
G01X365370Y270561D02*
X358882Y264336D01*
G01X364721Y270164D02*
X358929Y264609D01*
G01X364314Y270001D02*
X358978Y264882D01*
G01X364363Y270275D02*
X359027Y265156D01*
G01X364410Y270548D02*
X359073Y265429D01*
G01X364458Y270821D02*
X359122Y265702D01*
G01X364387Y270980D02*
X359171Y265975D01*
G01X364150Y270980D02*
X359217Y266248D01*
G01X363912Y270980D02*
X359265Y266522D01*
G01X363676Y270980D02*
X359314Y266795D01*
G01X363440Y270980D02*
X359362Y267068D01*
G01X363203Y270980D02*
X359409Y267341D01*
G01X362966Y270980D02*
X359458Y267615D01*
G01X362730Y270980D02*
X359506Y267888D01*
G01X362492Y270980D02*
X359553Y268161D01*
G01X362255Y270980D02*
X359602Y268434D01*
G01X356180Y267878D02*
X349771Y261731D01*
G01X356124Y268054D02*
X349576Y261772D01*
G01X356059Y268216D02*
X349372Y261802D01*
G01X355991Y268379D02*
X349163Y261829D01*
G01X355923Y268542D02*
X348945Y261847D01*
G01X355857Y268705D02*
X348723Y261862D01*
G01X351498Y264750D02*
X348496Y261871D01*
G01X355791Y268868D02*
X351703Y264947D01*
G01X351339Y264825D02*
X348264Y261876D01*
G01X355708Y269016D02*
X351750Y265220D01*
G01X355606Y269146D02*
X351797Y265493D01*
G01X351180Y264899D02*
X348024Y261872D01*
G01X351009Y264964D02*
X347752Y261838D01*
G01X355506Y269276D02*
X351823Y265744D01*
G01X355404Y269406D02*
X351837Y265985D01*
G01X347479Y261804D02*
X350831Y265020D01*
G01X347207Y261770D02*
X350653Y265076D01*
G01X355302Y269536D02*
X351816Y266191D01*
G01X346926Y261728D02*
X350474Y265132D01*
G01X355202Y269666D02*
X351786Y266390D01*
G01X355099Y269797D02*
X351728Y266562D01*
G01X354967Y269896D02*
X351667Y266730D01*
G01X354836Y269997D02*
X351576Y266870D01*
G01X354703Y270097D02*
X351484Y267009D01*
G01X354570Y270197D02*
X351368Y267125D01*
G01X354437Y270297D02*
X351245Y267234D01*
G01X354305Y270397D02*
X351110Y267332D01*
G01X354163Y270487D02*
X350957Y267412D01*
G01X354000Y270559D02*
X350803Y267492D01*
G01X353837Y270631D02*
X350620Y267544D01*
G01X353676Y270703D02*
X350435Y267593D01*
G01X353514Y270774D02*
X350236Y267630D01*
G01X353352Y270846D02*
X350017Y267647D01*
G01X353190Y270918D02*
X349798Y267664D01*
G01X353009Y270971D02*
X349560Y267662D01*
G01X352817Y271015D02*
X349317Y267658D01*
G01X352626Y271059D02*
X349075Y267653D01*
G01X352435Y271103D02*
X348822Y267637D01*
G01X352244Y271147D02*
X348568Y267620D01*
G01X352052Y271190D02*
X348306Y267597D01*
G01X351861Y271234D02*
X348033Y267561D01*
G01X351640Y271249D02*
X347756Y267523D01*
G01X351420Y271264D02*
X347457Y267463D01*
G01X351198Y271279D02*
X347149Y267395D01*
G01X362928Y262082D02*
X362879Y261809D01*
G01X362975Y262355D02*
X362928Y262082D01*
G01X363023Y262628D02*
X362975Y262355D01*
G01X363071Y262902D02*
X363023Y262628D01*
G01X358978Y264882D02*
X358929Y264609D01*
G01X363120Y263175D02*
X363071Y262902D01*
G01X358929Y264609D02*
X358882Y264336D01*
G01X359458Y267615D02*
X359506Y267888D01*
G01D02*
X359553Y268161D01*
G01X359602Y268434D02*
X359649Y268707D01*
G01X359362Y267068D02*
X359314Y266795D01*
G01D02*
X359265Y266522D01*
G01X359409Y267341D02*
X359458Y267615D01*
G01X359362Y267068D02*
X359409Y267341D01*
G01X359553Y268161D02*
X359602Y268434D01*
G01X359265Y266522D02*
X359217Y266248D01*
G01X358642Y262970D02*
X358594Y262696D01*
G01X358690Y263243D02*
X358642Y262970D01*
G01X358594Y262696D02*
X358547Y262423D01*
G01X359217Y266248D02*
X359171Y265975D01*
G01X358547Y262423D02*
X358498Y262150D01*
G01D02*
X358450Y261877D01*
G01X359027Y265156D02*
X358978Y264882D01*
G01X359073Y265429D02*
X359027Y265156D01*
G01X359122Y265702D02*
X359073Y265429D01*
G01X359171Y265975D02*
X359122Y265702D01*
G01X358882Y264336D02*
X358834Y264063D01*
G01X358785Y263789D02*
X358738Y263516D01*
G01X358834Y264063D02*
X358785Y263789D01*
G01X358738Y263516D02*
X358690Y263243D01*
G01X355985Y264056D02*
X355937Y263782D01*
G01X356128Y264875D02*
X356081Y264602D01*
G01X356176Y265148D02*
X356128Y264875D01*
G01X356032Y264329D02*
X355985Y264056D01*
G01X356081Y264602D02*
X356032Y264329D01*
G01X355793Y262963D02*
X355841Y263237D01*
G01X355744Y262689D02*
X355793Y262963D01*
G01X355841Y263237D02*
X355888Y263509D01*
G01X355937Y263782D02*
X355888Y263509D01*
G01X355649Y262143D02*
X355697Y262417D01*
G01X355601Y261870D02*
X355649Y262143D01*
G01X355697Y262417D02*
X355744Y262689D01*
G01X351750Y265220D02*
X351703Y264947D01*
G01X351797Y265493D02*
X351750Y265220D01*
G01X371654Y254095D02*
X371730Y254167D01*
G01X371418Y254095D02*
X371779Y254441D01*
G01X371182Y254095D02*
X371827Y254714D01*
G01X370944Y254095D02*
X371874Y254987D01*
G01X370708Y254095D02*
X371923Y255260D01*
G01X370472Y254095D02*
X371970Y255533D01*
G01X370234Y254095D02*
X372018Y255807D01*
G01X369997Y254095D02*
X372067Y256081D01*
G01X369761Y254095D02*
X372114Y256353D01*
G01X369523Y254095D02*
X372162Y256626D01*
G01X369286Y254095D02*
X372210Y256900D01*
G01X369050Y254095D02*
X372258Y257173D01*
G01X368813Y254095D02*
X372305Y257446D01*
G01X368575Y254095D02*
X372354Y257719D01*
G01X368339Y254095D02*
X372402Y257992D01*
G01X368102Y254095D02*
X372449Y258266D01*
G01X367865Y254095D02*
X372498Y258538D01*
G01X367629Y254095D02*
X372545Y258812D01*
G01X367391Y254095D02*
X372593Y259085D01*
G01X367300Y254235D02*
X372642Y259359D01*
G01X367349Y254508D02*
X372689Y259631D01*
G01X367397Y254781D02*
X372737Y259904D01*
G01X367444Y255055D02*
X372785Y260177D01*
G01X367493Y255328D02*
X372833Y260451D01*
G01X367541Y255601D02*
X372880Y260724D01*
G01X367588Y255874D02*
X372929Y260997D01*
G01X367637Y256148D02*
X372977Y261271D01*
G01X367686Y256422D02*
X373024Y261544D01*
G01X367733Y256694D02*
X373073Y261817D01*
G01X367781Y256968D02*
X373120Y262090D01*
G01X367829Y257241D02*
X373168Y262363D01*
G01X367877Y257515D02*
X373217Y262637D01*
G01X367924Y257788D02*
X373264Y262910D01*
G01X367973Y258061D02*
X373312Y263182D01*
G01X368022Y258334D02*
X373361Y263456D01*
G01X368069Y258607D02*
X373401Y263723D01*
G01X368117Y258881D02*
X373432Y263980D01*
G01X368166Y259154D02*
X373464Y264236D01*
G01X368213Y259427D02*
X373495Y264494D01*
G01X368261Y259701D02*
X373526Y264752D01*
G01X368310Y259974D02*
X373559Y265009D01*
G01X368357Y260247D02*
X373588Y265266D01*
G01X368404Y260521D02*
X373594Y265498D01*
G01X373591Y265723D02*
X368453Y260794D01*
G01X368502Y261067D02*
X373590Y265949D01*
G01X368550Y261340D02*
X373588Y266174D01*
G01X368597Y261614D02*
X373586Y266400D01*
G01X369050Y254095D02*
X369286D01*
G01X369761D02*
X369997D01*
G01X369523D02*
X369761D01*
G01X369286D02*
X369523D01*
G01X369997D02*
X370234D01*
G01D02*
X370472D01*
G01D02*
X370708D01*
G01X367349Y254508D02*
X367300Y254235D01*
G01X367397Y254781D02*
X367349Y254508D01*
G01X367391Y254095D02*
X367629D01*
G01D02*
X367865D01*
G01X367444Y255055D02*
X367397Y254781D01*
G01X367300Y254235D02*
X367276Y254095D01*
X367391D01*
G01X367541Y255601D02*
X367493Y255328D01*
G01D02*
X367444Y255055D01*
G01X368813Y254095D02*
X369050D01*
G01X367865D02*
X368102D01*
G01X368575D02*
X368813D01*
G01X368102D02*
X368339D01*
G01D02*
X368575D01*
G01X367588Y255874D02*
X367541Y255601D01*
G01X367924Y257788D02*
X367877Y257515D01*
G01X368357Y260247D02*
X368310Y259974D01*
G01D02*
X368261Y259701D01*
G01X368166Y259154D02*
X368117Y258881D01*
G01X368213Y259427D02*
X368166Y259154D01*
G01X368261Y259701D02*
X368213Y259427D01*
G01X367829Y257241D02*
X367781Y256968D01*
G01D02*
X367733Y256694D01*
G01X368117Y258881D02*
X368069Y258607D01*
G01X367733Y256694D02*
X367686Y256422D01*
G01D02*
X367637Y256148D01*
G01X368069Y258607D02*
X368022Y258334D01*
G01D02*
X367973Y258061D01*
G01X367637Y256148D02*
X367588Y255874D01*
G01X367877Y257515D02*
X367829Y257241D01*
G01X367973Y258061D02*
X367924Y257788D01*
G01X368404Y260521D02*
X368357Y260247D01*
G01X368646Y261887D02*
X368597Y261614D01*
G01X368502Y261067D02*
X368453Y260794D01*
G01X368597Y261614D02*
X368550Y261340D01*
G01X371923Y255260D02*
X371874Y254987D01*
G01X371827Y254714D02*
X371779Y254441D01*
G01X372449Y258266D02*
X372402Y257992D01*
G01X371874Y254987D02*
X371827Y254714D01*
G01X372498Y258538D02*
X372449Y258266D01*
G01X372593Y259085D02*
X372545Y258812D01*
G01X371779Y254441D02*
X371730Y254167D01*
G01X372642Y259359D02*
X372593Y259085D01*
G01X372545Y258812D02*
X372498Y258538D01*
G01X371654Y254095D02*
X371718D01*
X371730Y254167D01*
G01X372162Y256626D02*
X372114Y256353D01*
G01X372258Y257173D02*
X372210Y256900D01*
G01D02*
X372162Y256626D01*
G01X372305Y257446D02*
X372258Y257173D01*
G01X372354Y257719D02*
X372305Y257446D01*
G01X372018Y255807D02*
X371970Y255533D01*
G01X372402Y257992D02*
X372354Y257719D01*
G01X371970Y255533D02*
X371923Y255260D01*
G01X372067Y256081D02*
X372018Y255807D01*
G01X372114Y256353D02*
X372067Y256081D01*
G01X372977Y261271D02*
X372929Y260997D01*
G01X373073Y261817D02*
X373024Y261544D01*
G01X372689Y259631D02*
X372642Y259359D01*
G01X370944Y254095D02*
X371182D01*
G01X370708D02*
X370944D01*
G01X371182D02*
X371418D01*
G01X372833Y260451D02*
X372785Y260177D01*
G01X372880Y260724D02*
X372833Y260451D01*
G01X372785Y260177D02*
X372737Y259904D01*
G01D02*
X372689Y259631D01*
G01X371418Y254095D02*
X371654D01*
G01X373024Y261544D02*
X372977Y261271D01*
G01X372929Y260997D02*
X372880Y260724D01*
G01X368404Y260521D02*
X368453Y260794D01*
G01X368550Y261340D02*
X368502Y261067D01*
G01X371654Y254095D02*
X371730Y254167D01*
G01X371418Y254095D02*
X371779Y254441D01*
G01X371182Y254095D02*
X371827Y254714D01*
G01X370944Y254095D02*
X371874Y254987D01*
G01X370708Y254095D02*
X371923Y255260D01*
G01X370472Y254095D02*
X371970Y255533D01*
G01X370234Y254095D02*
X372018Y255807D01*
G01X369997Y254095D02*
X372067Y256081D01*
G01X369761Y254095D02*
X372114Y256353D01*
G01X369523Y254095D02*
X372162Y256626D01*
G01X369286Y254095D02*
X372210Y256900D01*
G01X369050Y254095D02*
X372258Y257173D01*
G01X368813Y254095D02*
X372305Y257446D01*
G01X368575Y254095D02*
X372354Y257719D01*
G01X368339Y254095D02*
X372402Y257992D01*
G01X368102Y254095D02*
X372449Y258266D01*
G01X367865Y254095D02*
X372498Y258538D01*
G01X367629Y254095D02*
X372545Y258812D01*
G01X367391Y254095D02*
X372593Y259085D01*
G01X367300Y254235D02*
X372642Y259359D01*
G01X367349Y254508D02*
X372689Y259631D01*
G01X367397Y254781D02*
X372737Y259904D01*
G01X367444Y255055D02*
X372785Y260177D01*
G01X367493Y255328D02*
X372833Y260451D01*
G01X367541Y255601D02*
X372880Y260724D01*
G01X367588Y255874D02*
X372929Y260997D01*
G01X367637Y256148D02*
X372977Y261271D01*
G01X367686Y256422D02*
X373024Y261544D01*
G01X367733Y256694D02*
X373073Y261817D01*
G01X367781Y256968D02*
X373120Y262090D01*
G01X367829Y257241D02*
X373168Y262363D01*
G01X367877Y257515D02*
X373217Y262637D01*
G01X367924Y257788D02*
X373264Y262910D01*
G01X367973Y258061D02*
X373312Y263182D01*
G01X368022Y258334D02*
X373361Y263456D01*
G01X368069Y258607D02*
X373401Y263723D01*
G01X368117Y258881D02*
X373432Y263980D01*
G01X368166Y259154D02*
X373464Y264236D01*
G01X368213Y259427D02*
X373495Y264494D01*
G01X368261Y259701D02*
X373526Y264752D01*
G01X368310Y259974D02*
X373559Y265009D01*
G01X368357Y260247D02*
X373588Y265266D01*
G01X368404Y260521D02*
X373594Y265498D01*
G01X373591Y265723D02*
X368453Y260794D01*
G01X368502Y261067D02*
X373590Y265949D01*
G01X368550Y261340D02*
X373588Y266174D01*
G01X368597Y261614D02*
X373586Y266400D01*
G01X369050Y254095D02*
X369286D01*
G01X369761D02*
X369997D01*
G01X369523D02*
X369761D01*
G01X369286D02*
X369523D01*
G01X369997D02*
X370234D01*
G01D02*
X370472D01*
G01D02*
X370708D01*
G01X367349Y254508D02*
X367300Y254235D01*
G01X367397Y254781D02*
X367349Y254508D01*
G01X367391Y254095D02*
X367629D01*
G01D02*
X367865D01*
G01X367444Y255055D02*
X367397Y254781D01*
G01X367300Y254235D02*
X367276Y254095D01*
X367391D01*
G01X367541Y255601D02*
X367493Y255328D01*
G01D02*
X367444Y255055D01*
G01X368813Y254095D02*
X369050D01*
G01X367865D02*
X368102D01*
G01X368575D02*
X368813D01*
G01X368102D02*
X368339D01*
G01D02*
X368575D01*
G01X367588Y255874D02*
X367541Y255601D01*
G01X367924Y257788D02*
X367877Y257515D01*
G01X368357Y260247D02*
X368310Y259974D01*
G01D02*
X368261Y259701D01*
G01X368166Y259154D02*
X368117Y258881D01*
G01X368213Y259427D02*
X368166Y259154D01*
G01X368261Y259701D02*
X368213Y259427D01*
G01X367829Y257241D02*
X367781Y256968D01*
G01D02*
X367733Y256694D01*
G01X368117Y258881D02*
X368069Y258607D01*
G01X367733Y256694D02*
X367686Y256422D01*
G01D02*
X367637Y256148D01*
G01X368069Y258607D02*
X368022Y258334D01*
G01D02*
X367973Y258061D01*
G01X367637Y256148D02*
X367588Y255874D01*
G01X367877Y257515D02*
X367829Y257241D01*
G01X367973Y258061D02*
X367924Y257788D01*
G01X368404Y260521D02*
X368357Y260247D01*
G01X368646Y261887D02*
X368597Y261614D01*
G01X368502Y261067D02*
X368453Y260794D01*
G01X368597Y261614D02*
X368550Y261340D01*
G01X371923Y255260D02*
X371874Y254987D01*
G01X371827Y254714D02*
X371779Y254441D01*
G01X372449Y258266D02*
X372402Y257992D01*
G01X371874Y254987D02*
X371827Y254714D01*
G01X372498Y258538D02*
X372449Y258266D01*
G01X372593Y259085D02*
X372545Y258812D01*
G01X371779Y254441D02*
X371730Y254167D01*
G01X372642Y259359D02*
X372593Y259085D01*
G01X372545Y258812D02*
X372498Y258538D01*
G01X371654Y254095D02*
X371718D01*
X371730Y254167D01*
G01X372162Y256626D02*
X372114Y256353D01*
G01X372258Y257173D02*
X372210Y256900D01*
G01D02*
X372162Y256626D01*
G01X372305Y257446D02*
X372258Y257173D01*
G01X372354Y257719D02*
X372305Y257446D01*
G01X372018Y255807D02*
X371970Y255533D01*
G01X372402Y257992D02*
X372354Y257719D01*
G01X371970Y255533D02*
X371923Y255260D01*
G01X372067Y256081D02*
X372018Y255807D01*
G01X372114Y256353D02*
X372067Y256081D01*
G01X372977Y261271D02*
X372929Y260997D01*
G01X373073Y261817D02*
X373024Y261544D01*
G01X372689Y259631D02*
X372642Y259359D01*
G01X370944Y254095D02*
X371182D01*
G01X370708D02*
X370944D01*
G01X371182D02*
X371418D01*
G01X372833Y260451D02*
X372785Y260177D01*
G01X372880Y260724D02*
X372833Y260451D01*
G01X372785Y260177D02*
X372737Y259904D01*
G01D02*
X372689Y259631D01*
G01X371418Y254095D02*
X371654D01*
G01X373024Y261544D02*
X372977Y261271D01*
G01X372929Y260997D02*
X372880Y260724D01*
G01X368404Y260521D02*
X368453Y260794D01*
G01X368550Y261340D02*
X368502Y261067D01*
G01X377081Y266798D02*
X384459Y273876D01*
G01X376845Y266798D02*
X384508Y274150D01*
G01X376608Y266798D02*
X384556Y274424D01*
G01X376370Y266798D02*
X384603Y274696D01*
G01X376134Y266798D02*
X384652Y274969D01*
G01X375961Y266859D02*
X384700Y275243D01*
G01X384748Y275517D02*
X376008Y267133D01*
G01X384796Y275790D02*
X376057Y267406D01*
G01X384845Y276062D02*
X376104Y267679D01*
G01X376153Y267953D02*
X379308Y270980D01*
G01X376201Y268226D02*
X379072Y270980D01*
G01X376248Y268499D02*
X378835Y270980D01*
G01X368646Y261887D02*
X373586Y266625D01*
G01X368693Y262160D02*
X373580Y266847D01*
G01X368741Y262433D02*
X373545Y267041D01*
G01X368790Y262707D02*
X373510Y267235D01*
G01X373474Y267429D02*
X368839Y262980D01*
G01X373441Y267622D02*
X368885Y263252D01*
G01X373405Y267816D02*
X368917Y263511D01*
G01X373371Y268010D02*
X368952Y263771D01*
G01X373325Y268195D02*
X368985Y264031D01*
G01X373257Y268356D02*
X369016Y264287D01*
G01X373190Y268518D02*
X369018Y264516D01*
G01X373120Y268679D02*
X369020Y264746D01*
G01X373051Y268841D02*
X369023Y264975D01*
G01X372983Y269002D02*
X369012Y265192D01*
G01X372916Y269163D02*
X368980Y265388D01*
G01X372832Y269312D02*
X368947Y265584D01*
G01X372728Y269440D02*
X368914Y265780D01*
G01X372625Y269568D02*
X368848Y265944D01*
G01X372522Y269696D02*
X368779Y266104D01*
G01X372419Y269825D02*
X368708Y266264D01*
G01X372316Y269953D02*
X368613Y266402D01*
G01X372213Y270081D02*
X368505Y266524D01*
G01X372094Y270193D02*
X368396Y266647D01*
G01X371954Y270287D02*
X368269Y266752D01*
G01X371814Y270380D02*
X368120Y266836D01*
G01X371676Y270475D02*
X367973Y266922D01*
G01X371538Y270568D02*
X367806Y266989D01*
G01X371399Y270663D02*
X367621Y267038D01*
G01X371260Y270757D02*
X367433Y267087D01*
G01X371098Y270829D02*
X367230Y267118D01*
G01X370923Y270888D02*
X367009Y267133D01*
G01X370746Y270946D02*
X366788Y267148D01*
G01X370569Y271004D02*
X366545Y267143D01*
G01X370393Y271062D02*
X366290Y267125D01*
G01X370217Y271120D02*
X366034Y267106D01*
G01X370040Y271178D02*
X365718Y267031D01*
G01X376248Y268499D02*
X376297Y268772D01*
G01X376201Y268226D02*
X376248Y268499D01*
G01X376153Y267953D02*
X376201Y268226D01*
G01X377081Y266798D02*
X377318D01*
G01X376845D02*
X377081D01*
G01X376608D02*
X376845D01*
G01X376057Y267406D02*
X376008Y267133D01*
G01X376104Y267679D02*
X376057Y267406D01*
G01X376008Y267133D02*
X375961Y266859D01*
G01X376104Y267679D02*
X376153Y267953D01*
G01X376370Y266798D02*
X376608D01*
G01X375961Y266859D02*
X375950Y266798D01*
X376134D01*
G01D02*
X376370D01*
G01X368839Y262980D02*
X368790Y262707D01*
G01X373264Y262910D02*
X373217Y262637D01*
G01X373312Y263182D02*
X373264Y262910D01*
G01X368790Y262707D02*
X368741Y262433D01*
G01X373168Y262363D02*
X373120Y262090D01*
G01D02*
X373073Y261817D01*
G01X373217Y262637D02*
X373168Y262363D01*
G01X368693Y262160D02*
X368646Y261887D01*
G01X373361Y263456D02*
X373312Y263182D01*
G01X368741Y262433D02*
X368693Y262160D01*
G01X377081Y266798D02*
X384459Y273876D01*
G01X376845Y266798D02*
X384508Y274150D01*
G01X376608Y266798D02*
X384556Y274424D01*
G01X376370Y266798D02*
X384603Y274696D01*
G01X376134Y266798D02*
X384652Y274969D01*
G01X375961Y266859D02*
X384700Y275243D01*
G01X384748Y275517D02*
X376008Y267133D01*
G01X384796Y275790D02*
X376057Y267406D01*
G01X384845Y276062D02*
X376104Y267679D01*
G01X376153Y267953D02*
X379308Y270980D01*
G01X376201Y268226D02*
X379072Y270980D01*
G01X376248Y268499D02*
X378835Y270980D01*
G01X368646Y261887D02*
X373586Y266625D01*
G01X368693Y262160D02*
X373580Y266847D01*
G01X368741Y262433D02*
X373545Y267041D01*
G01X368790Y262707D02*
X373510Y267235D01*
G01X373474Y267429D02*
X368839Y262980D01*
G01X373441Y267622D02*
X368885Y263252D01*
G01X373405Y267816D02*
X368917Y263511D01*
G01X373371Y268010D02*
X368952Y263771D01*
G01X373325Y268195D02*
X368985Y264031D01*
G01X373257Y268356D02*
X369016Y264287D01*
G01X373190Y268518D02*
X369018Y264516D01*
G01X373120Y268679D02*
X369020Y264746D01*
G01X373051Y268841D02*
X369023Y264975D01*
G01X372983Y269002D02*
X369012Y265192D01*
G01X372916Y269163D02*
X368980Y265388D01*
G01X372832Y269312D02*
X368947Y265584D01*
G01X372728Y269440D02*
X368914Y265780D01*
G01X372625Y269568D02*
X368848Y265944D01*
G01X372522Y269696D02*
X368779Y266104D01*
G01X372419Y269825D02*
X368708Y266264D01*
G01X372316Y269953D02*
X368613Y266402D01*
G01X372213Y270081D02*
X368505Y266524D01*
G01X372094Y270193D02*
X368396Y266647D01*
G01X371954Y270287D02*
X368269Y266752D01*
G01X371814Y270380D02*
X368120Y266836D01*
G01X371676Y270475D02*
X367973Y266922D01*
G01X371538Y270568D02*
X367806Y266989D01*
G01X371399Y270663D02*
X367621Y267038D01*
G01X371260Y270757D02*
X367433Y267087D01*
G01X371098Y270829D02*
X367230Y267118D01*
G01X370923Y270888D02*
X367009Y267133D01*
G01X370746Y270946D02*
X366788Y267148D01*
G01X370569Y271004D02*
X366545Y267143D01*
G01X370393Y271062D02*
X366290Y267125D01*
G01X370217Y271120D02*
X366034Y267106D01*
G01X370040Y271178D02*
X365718Y267031D01*
G01X376248Y268499D02*
X376297Y268772D01*
G01X376201Y268226D02*
X376248Y268499D01*
G01X376153Y267953D02*
X376201Y268226D01*
G01X377081Y266798D02*
X377318D01*
G01X376845D02*
X377081D01*
G01X376608D02*
X376845D01*
G01X376057Y267406D02*
X376008Y267133D01*
G01X376104Y267679D02*
X376057Y267406D01*
G01X376008Y267133D02*
X375961Y266859D01*
G01X376104Y267679D02*
X376153Y267953D01*
G01X376370Y266798D02*
X376608D01*
G01X375961Y266859D02*
X375950Y266798D01*
X376134D01*
G01D02*
X376370D01*
G01X368839Y262980D02*
X368790Y262707D01*
G01X373264Y262910D02*
X373217Y262637D01*
G01X373312Y263182D02*
X373264Y262910D01*
G01X368790Y262707D02*
X368741Y262433D01*
G01X373168Y262363D02*
X373120Y262090D01*
G01D02*
X373073Y261817D01*
G01X373217Y262637D02*
X373168Y262363D01*
G01X368693Y262160D02*
X368646Y261887D01*
G01X373361Y263456D02*
X373312Y263182D01*
G01X368741Y262433D02*
X368693Y262160D01*
G01X362019Y270980D02*
X359649Y268707D01*
G01X361781Y270980D02*
X359697Y268981D01*
G01X361544Y270980D02*
X359746Y269253D01*
G01X361308Y270980D02*
X359793Y269527D01*
G01X361071Y270980D02*
X359841Y269801D01*
G01X360833Y270980D02*
X359889Y270073D01*
G01X360597Y270980D02*
X359937Y270347D01*
G01X360360Y270980D02*
X359984Y270620D01*
G01X360123Y270980D02*
X360033Y270893D01*
G01X364458Y270821D02*
X364486Y270980D01*
X364387D01*
G01X364410Y270548D02*
X364458Y270821D01*
G01X364314Y270001D02*
X364363Y270275D01*
G01D02*
X364410Y270548D01*
G01X363912Y270980D02*
X363676D01*
G01D02*
X363440D01*
G01X364387D02*
X364150D01*
G01D02*
X363912D01*
G01X363440D02*
X363203D01*
G01X361781D02*
X361544D01*
G01X360597D02*
X360360D01*
G01X361071D02*
X360833D01*
G01X363203D02*
X362966D01*
G01X361308D02*
X361071D01*
G01X361544D02*
X361308D01*
G01X360833D02*
X360597D01*
G01X362492D02*
X362255D01*
G01X362730D02*
X362492D01*
G01X362019D02*
X361781D01*
G01X362966D02*
X362730D01*
G01X360360D02*
X360123D01*
G01X362255D02*
X362019D01*
G01X359649Y268707D02*
X359697Y268981D01*
G01X360123Y270980D02*
X360048D01*
X360033Y270893D01*
G01X359984Y270620D02*
X360033Y270893D01*
G01X359746Y269253D02*
X359793Y269527D01*
G01X359697Y268981D02*
X359746Y269253D01*
G01X359937Y270347D02*
X359984Y270620D01*
G01X359793Y269527D02*
X359841Y269801D01*
G01D02*
X359889Y270073D01*
G01D02*
X359937Y270347D01*
G01X362019Y270980D02*
X359649Y268707D01*
G01X361781Y270980D02*
X359697Y268981D01*
G01X361544Y270980D02*
X359746Y269253D01*
G01X361308Y270980D02*
X359793Y269527D01*
G01X361071Y270980D02*
X359841Y269801D01*
G01X360833Y270980D02*
X359889Y270073D01*
G01X360597Y270980D02*
X359937Y270347D01*
G01X360360Y270980D02*
X359984Y270620D01*
G01X360123Y270980D02*
X360033Y270893D01*
G01X364458Y270821D02*
X364486Y270980D01*
X364387D01*
G01X364410Y270548D02*
X364458Y270821D01*
G01X364314Y270001D02*
X364363Y270275D01*
G01D02*
X364410Y270548D01*
G01X363912Y270980D02*
X363676D01*
G01D02*
X363440D01*
G01X364387D02*
X364150D01*
G01D02*
X363912D01*
G01X363440D02*
X363203D01*
G01X361781D02*
X361544D01*
G01X360597D02*
X360360D01*
G01X361071D02*
X360833D01*
G01X363203D02*
X362966D01*
G01X361308D02*
X361071D01*
G01X361544D02*
X361308D01*
G01X360833D02*
X360597D01*
G01X362492D02*
X362255D01*
G01X362730D02*
X362492D01*
G01X362019D02*
X361781D01*
G01X362966D02*
X362730D01*
G01X360360D02*
X360123D01*
G01X362255D02*
X362019D01*
G01X359649Y268707D02*
X359697Y268981D01*
G01X360123Y270980D02*
X360048D01*
X360033Y270893D01*
G01X359984Y270620D02*
X360033Y270893D01*
G01X359746Y269253D02*
X359793Y269527D01*
G01X359697Y268981D02*
X359746Y269253D01*
G01X359937Y270347D02*
X359984Y270620D01*
G01X359793Y269527D02*
X359841Y269801D01*
G01D02*
X359889Y270073D01*
G01D02*
X359937Y270347D01*
G01X376297Y268772D02*
X378599Y270980D01*
G01X376344Y269046D02*
X378361Y270980D01*
G01X376393Y269319D02*
X378124Y270980D01*
G01X376441Y269592D02*
X377888Y270980D01*
G01X376490Y269865D02*
X377651Y270980D01*
G01X377413D02*
X376537Y270139D01*
G01X376585Y270412D02*
X377177Y270980D01*
G01X376633Y270686D02*
X376940Y270980D01*
G01X376681Y270958D02*
X376704Y270980D01*
G01X376585Y270412D02*
X376633Y270686D01*
G01X376537Y270139D02*
X376490Y269865D01*
G01X376585Y270412D02*
X376537Y270139D01*
G01X376344Y269046D02*
X376393Y269319D01*
G01X376441Y269592D02*
X376490Y269865D01*
G01X376393Y269319D02*
X376441Y269592D01*
G01X376297Y268772D02*
X376344Y269046D01*
G01X376633Y270686D02*
X376681Y270958D01*
G01D02*
X376685Y270980D01*
X376704D01*
G01X377177D02*
X376940D01*
G01D02*
X376704D01*
G01X376297Y268772D02*
X378599Y270980D01*
G01X376344Y269046D02*
X378361Y270980D01*
G01X376393Y269319D02*
X378124Y270980D01*
G01X376441Y269592D02*
X377888Y270980D01*
G01X376490Y269865D02*
X377651Y270980D01*
G01X377413D02*
X376537Y270139D01*
G01X376585Y270412D02*
X377177Y270980D01*
G01X376633Y270686D02*
X376940Y270980D01*
G01X376681Y270958D02*
X376704Y270980D01*
G01X376585Y270412D02*
X376633Y270686D01*
G01X376537Y270139D02*
X376490Y269865D01*
G01X376585Y270412D02*
X376537Y270139D01*
G01X376344Y269046D02*
X376393Y269319D01*
G01X376441Y269592D02*
X376490Y269865D01*
G01X376393Y269319D02*
X376441Y269592D01*
G01X376297Y268772D02*
X376344Y269046D01*
G01X376633Y270686D02*
X376681Y270958D01*
G01D02*
X376685Y270980D01*
X376704D01*
G01X377177D02*
X376940D01*
G01D02*
X376704D01*
G01X401736Y254095D02*
X401819Y254175D01*
G01X401499Y254095D02*
X401868Y254449D01*
G01X401262Y254095D02*
X401916Y254723D01*
G01X401026Y254095D02*
X401963Y254995D01*
G01X400788Y254095D02*
X402010Y255267D01*
G01X400551Y254095D02*
X402059Y255541D01*
G01X400314Y254095D02*
X402107Y255815D01*
G01X400078Y254095D02*
X402154Y256087D01*
G01X399842Y254095D02*
X402203Y256360D01*
G01X399604Y254095D02*
X402251Y256634D01*
G01X399367Y254095D02*
X402298Y256908D01*
G01X399130Y254095D02*
X402347Y257180D01*
G01X398894Y254095D02*
X402394Y257453D01*
G01X398656Y254095D02*
X402442Y257726D01*
G01X398419Y254095D02*
X402491Y258000D01*
G01X398183Y254095D02*
X402538Y258272D01*
G01X397947Y254095D02*
X402586Y258545D01*
G01X397710Y254095D02*
X402633Y258819D01*
G01X397472Y254095D02*
X402682Y259092D01*
G01X397395Y254247D02*
X402729Y259365D01*
G01X397442Y254521D02*
X402777Y259638D01*
G01X397491Y254794D02*
X402826Y259912D01*
G01X402873Y260185D02*
X397539Y255068D01*
G01X397155Y254927D02*
X402921Y260457D01*
G01X396481Y254507D02*
X402968Y260730D01*
G01X396007Y254280D02*
X403017Y261004D01*
G01X395602Y254118D02*
X403064Y261277D01*
G01X395265Y254023D02*
X403112Y261550D01*
G01X394929Y253927D02*
X403161Y261823D01*
G01X394610Y253849D02*
X403208Y262097D01*
G01X394346Y253822D02*
X403256Y262370D01*
G01X394083Y253798D02*
X403303Y262643D01*
G01X393820Y253771D02*
X403352Y262915D01*
G01X393555Y253746D02*
X403399Y263189D01*
G01X393322Y253749D02*
X403447Y263462D01*
G01X393094Y253757D02*
X403496Y263735D01*
G01X403543Y264008D02*
X392871Y253771D01*
G01X403591Y264282D02*
X398257Y259166D01*
G01X392660Y253795D02*
X397297Y258244D01*
G01X392450Y253821D02*
X396725Y257922D01*
G01X403639Y264555D02*
X398305Y259439D01*
G01X403687Y264828D02*
X398354Y259711D01*
G01X392248Y253853D02*
X396344Y257783D01*
G01X403734Y265100D02*
X398401Y259984D01*
G01X392052Y253893D02*
X395963Y257644D01*
G01X403782Y265374D02*
X398449Y260258D01*
G01X391857Y253933D02*
X395680Y257602D01*
G01X403808Y265625D02*
X398498Y260531D01*
G01X391671Y253984D02*
X395408Y257568D01*
G01X403827Y265871D02*
X398545Y260804D01*
G01X391491Y254037D02*
X395137Y257535D01*
G01X391310Y254091D02*
X394868Y257504D01*
G01X403847Y266117D02*
X398592Y261077D01*
G01X391141Y254156D02*
X394648Y257520D01*
G01X403867Y266364D02*
X398517Y261231D01*
G01X390974Y254224D02*
X394429Y257537D01*
G01X403888Y266612D02*
X398374Y261323D01*
G01X390807Y254291D02*
X394212Y257556D01*
G01X403889Y266840D02*
X398225Y261406D01*
G01X390651Y254368D02*
X394026Y257605D01*
G01X403862Y267040D02*
X398073Y261487D01*
G01X390498Y254449D02*
X393840Y257653D01*
G01X403835Y267242D02*
X397908Y261556D01*
G01X390346Y254530D02*
X393662Y257712D01*
G01X403806Y267443D02*
X397738Y261621D01*
G01X390201Y254618D02*
X393510Y257792D01*
G01X403779Y267643D02*
X397559Y261676D01*
G01X390064Y254712D02*
X393357Y257872D01*
G01X389924Y254807D02*
X393224Y257973D01*
G01X389791Y254907D02*
X393105Y258085D01*
G01X389668Y255014D02*
X392988Y258201D01*
G01X389543Y255122D02*
X392901Y258344D01*
G01X389421Y255233D02*
X392816Y258489D01*
G01X389311Y255355D02*
X392756Y258660D01*
G01X389203Y255477D02*
X392705Y258837D01*
G01X389093Y255600D02*
X392676Y259036D01*
G01X388998Y255735D02*
X392660Y259249D01*
G01X388903Y255872D02*
X392672Y259488D01*
G01X388809Y256009D02*
X392698Y259739D01*
G01X388726Y256157D02*
X392816Y260080D01*
G01X388649Y256310D02*
X392942Y260428D01*
G01X394108Y261547D02*
X397882Y265167D01*
G01X388572Y256463D02*
X393604Y261291D01*
G01X393643Y261328D02*
X397681Y265202D01*
G01X388501Y256623D02*
X397482Y265237D01*
G01X388442Y256793D02*
X397281Y265272D01*
G01X388382Y256963D02*
X397072Y265300D01*
G01X388328Y257138D02*
X396848Y265311D01*
G01X388287Y257326D02*
X396623Y265323D01*
G01X388248Y257514D02*
X396399Y265335D01*
G01X388210Y257705D02*
X396176Y265347D01*
G01X388191Y257915D02*
X395931Y265341D01*
G01X388172Y258124D02*
X395679Y265325D01*
G01X384196Y254538D02*
X384689Y255010D01*
G01X395425Y265310D02*
X388154Y258334D01*
G01X383712Y254300D02*
X384793Y255338D01*
G01X388160Y258567D02*
X395172Y265293D01*
G01X388165Y258799D02*
X394918Y265278D01*
G01X383326Y254157D02*
X384898Y255665D01*
G01X388172Y259033D02*
X394662Y265259D01*
G01X382954Y254027D02*
X385001Y255992D01*
G01X382646Y253958D02*
X385105Y256318D01*
G01X388204Y259292D02*
X394365Y265201D01*
G01X382337Y253890D02*
X385210Y256645D01*
G01X388238Y259551D02*
X394066Y265142D01*
G01X382029Y253822D02*
X385314Y256973D01*
G01X388282Y259821D02*
X393768Y265083D01*
G01X381771Y253801D02*
X385417Y257299D01*
G01X388368Y260131D02*
X393471Y265025D01*
G01X381513Y253782D02*
X385521Y257626D01*
G01X388455Y260441D02*
X393128Y264924D01*
G01X381256Y253763D02*
X385625Y257953D01*
G01X388543Y260752D02*
X392753Y264792D01*
G01X388630Y261063D02*
X392379Y264659D01*
G01X380998Y253741D02*
X385729Y258281D01*
G01X388865Y261516D02*
X391956Y264482D01*
G01X380784Y253763D02*
X385833Y258607D01*
G01X380569Y253784D02*
X385937Y258934D01*
G01X380354Y253806D02*
X386041Y259261D01*
G01X380140Y253828D02*
X385188Y258670D01*
G01X379946Y253868D02*
X384596Y258329D01*
G01X379771Y253928D02*
X384183Y258160D01*
G01X379596Y253986D02*
X383829Y258048D01*
G01X379419Y254046D02*
X383559Y258016D01*
G01X379246Y254104D02*
X383293Y257988D01*
G01X379097Y254188D02*
X383069Y258000D01*
G01X378955Y254281D02*
X382859Y258026D01*
G01X378813Y254373D02*
X382665Y258068D01*
G01X378673Y254465D02*
X382501Y258137D01*
G01X378532Y254557D02*
X382349Y258219D01*
G01X378417Y254675D02*
X382232Y258333D01*
G01X378307Y254797D02*
X382132Y258465D01*
G01X378197Y254918D02*
X382055Y258618D01*
G01X378087Y255040D02*
X382004Y258797D01*
G01X377978Y255162D02*
X381967Y258988D01*
G01X377895Y255310D02*
X381960Y259208D01*
G01X377816Y255461D02*
X381958Y259435D01*
G01X377736Y255611D02*
X381987Y259688D01*
G01X377656Y255762D02*
X382019Y259947D01*
G01X377576Y255913D02*
X382063Y260217D01*
G01X377527Y256093D02*
X382112Y260490D01*
G01X377478Y256273D02*
X382159Y260763D01*
G01X377430Y256454D02*
X382208Y261037D01*
G01X377381Y256635D02*
X382255Y261311D01*
G01X377339Y256821D02*
X382303Y261583D01*
G01X377325Y257034D02*
X382352Y261856D01*
G01X377310Y257247D02*
X382399Y262130D01*
G01X377295Y257461D02*
X382448Y262404D01*
G01X377280Y257674D02*
X382495Y262676D01*
G01X377290Y257910D02*
X382543Y262949D01*
G01X377314Y258161D02*
X382592Y263223D01*
G01X377340Y258413D02*
X382639Y263496D01*
G01X377364Y258663D02*
X382688Y263770D01*
G01X377398Y258922D02*
X382736Y264042D01*
G01X377446Y259195D02*
X382783Y264316D01*
G01X377493Y259469D02*
X382832Y264590D01*
G01X382879Y264863D02*
X377542Y259742D01*
G01X377590Y260015D02*
X382928Y265135D01*
G01X377637Y260288D02*
X382976Y265409D01*
G01X377686Y260562D02*
X383024Y265683D01*
G01X377733Y260835D02*
X383072Y265955D01*
G01X377781Y261107D02*
X383119Y266229D01*
G01X377828Y261381D02*
X383168Y266502D01*
G01X377877Y261654D02*
X383216Y266776D01*
G01X400551Y254095D02*
X400788D01*
G01X400078D02*
X400314D01*
G01D02*
X400551D01*
G01X399604D02*
X399842D01*
G01D02*
X400078D01*
G01X401499D02*
X401736D01*
G01D02*
X401806D01*
X401819Y254175D01*
G01X399367Y254095D02*
X399604D01*
G01X400788D02*
X401026D01*
G01X401262D02*
X401499D01*
G01X401026D02*
X401262D01*
G01X397472D02*
X397710D01*
G01X397491Y254794D02*
X397442Y254521D01*
G01X397395Y254247D02*
X397368Y254095D01*
X397472D01*
G01X397442Y254521D02*
X397395Y254247D01*
G01X398894Y254095D02*
X399130D01*
G01X398656D02*
X398894D01*
G01X399130D02*
X399367D01*
G01X397947D02*
X398183D01*
G01D02*
X398419D01*
G01D02*
X398656D01*
G01X402826Y259912D02*
X402873Y260185D01*
G01D02*
X402921Y260457D01*
G01D02*
X402968Y260730D01*
G01X402729Y259365D02*
X402777Y259638D01*
G01X402682Y259092D02*
X402729Y259365D01*
G01X402777Y259638D02*
X402826Y259912D01*
G01X402633Y258819D02*
X402682Y259092D01*
G01X403112Y261550D02*
X403161Y261823D01*
G01X401819Y254175D02*
X401868Y254449D01*
G01X403064Y261277D02*
X403112Y261550D01*
G01X402968Y260730D02*
X403017Y261004D01*
G01D02*
X403064Y261277D01*
G01X402010Y255267D02*
X402059Y255541D01*
G01X402586Y258545D02*
X402633Y258819D01*
G01X402107Y255815D02*
X402154Y256087D01*
G01X402059Y255541D02*
X402107Y255815D01*
G01X401963Y254995D02*
X402010Y255267D01*
G01X401868Y254449D02*
X401916Y254723D01*
G01D02*
X401963Y254995D01*
G01X402442Y257726D02*
X402491Y258000D01*
G01X402538Y258272D02*
X402586Y258545D01*
G01X402394Y257453D02*
X402442Y257726D01*
G01X402491Y258000D02*
X402538Y258272D01*
G01X402203Y256360D02*
X402251Y256634D01*
G01X402154Y256087D02*
X402203Y256360D01*
G01X402251Y256634D02*
X402298Y256908D01*
G01D02*
X402347Y257180D01*
G01D02*
X402394Y257453D01*
G01X397710Y254095D02*
X397947D01*
G01X398498Y260531D02*
X398449Y260258D01*
G01D02*
X398401Y259984D01*
G01X398592Y261077D02*
X398545Y260804D01*
G01D02*
X398498Y260531D01*
G01X398305Y259439D02*
X398257Y259166D01*
G01X398401Y259984D02*
X398354Y259711D01*
G01D02*
X398305Y259439D01*
G01X397539Y255068D02*
X397491Y254794D01*
G01X377493Y259469D02*
X377446Y259195D01*
G01X377925Y261927D02*
X377877Y261654D01*
G01X385417Y257299D02*
X385314Y256973D01*
G01X385521Y257626D02*
X385417Y257299D01*
G01X385314Y256973D02*
X385210Y256645D01*
G01X385625Y257953D02*
X385521Y257626D01*
G01X385210Y256645D02*
X385105Y256318D01*
G01X385729Y258281D02*
X385625Y257953D01*
G01X385105Y256318D02*
X385001Y255992D01*
G01D02*
X384898Y255665D01*
G01D02*
X384793Y255338D01*
G01X377877Y261654D02*
X377828Y261381D01*
G01X385833Y258607D02*
X385729Y258281D01*
G01X377828Y261381D02*
X377781Y261107D01*
G01X385937Y258934D02*
X385833Y258607D01*
G01X386041Y259261D02*
X385937Y258934D01*
G01X384793Y255338D02*
X384689Y255010D01*
G01X377733Y260835D02*
X377686Y260562D01*
G01D02*
X377637Y260288D01*
G01X377781Y261107D02*
X377733Y260835D01*
G01X377637Y260288D02*
X377590Y260015D01*
G01X377493Y259469D02*
X377542Y259742D01*
G01X382159Y260763D02*
X382112Y260490D01*
G01D02*
X382063Y260217D01*
G01X377590Y260015D02*
X377542Y259742D01*
G01X382208Y261037D02*
X382255Y261311D01*
G01D02*
X382303Y261583D01*
G01X377446Y259195D02*
X377398Y258922D01*
G01X382208Y261037D02*
X382159Y260763D01*
G01X382303Y261583D02*
X382352Y261856D01*
G01X401736Y254095D02*
X401819Y254175D01*
G01X401499Y254095D02*
X401868Y254449D01*
G01X401262Y254095D02*
X401916Y254723D01*
G01X401026Y254095D02*
X401963Y254995D01*
G01X400788Y254095D02*
X402010Y255267D01*
G01X400551Y254095D02*
X402059Y255541D01*
G01X400314Y254095D02*
X402107Y255815D01*
G01X400078Y254095D02*
X402154Y256087D01*
G01X399842Y254095D02*
X402203Y256360D01*
G01X399604Y254095D02*
X402251Y256634D01*
G01X399367Y254095D02*
X402298Y256908D01*
G01X399130Y254095D02*
X402347Y257180D01*
G01X398894Y254095D02*
X402394Y257453D01*
G01X398656Y254095D02*
X402442Y257726D01*
G01X398419Y254095D02*
X402491Y258000D01*
G01X398183Y254095D02*
X402538Y258272D01*
G01X397947Y254095D02*
X402586Y258545D01*
G01X397710Y254095D02*
X402633Y258819D01*
G01X397472Y254095D02*
X402682Y259092D01*
G01X397395Y254247D02*
X402729Y259365D01*
G01X397442Y254521D02*
X402777Y259638D01*
G01X397491Y254794D02*
X402826Y259912D01*
G01X402873Y260185D02*
X397539Y255068D01*
G01X397155Y254927D02*
X402921Y260457D01*
G01X396481Y254507D02*
X402968Y260730D01*
G01X396007Y254280D02*
X403017Y261004D01*
G01X395602Y254118D02*
X403064Y261277D01*
G01X395265Y254023D02*
X403112Y261550D01*
G01X394929Y253927D02*
X403161Y261823D01*
G01X394610Y253849D02*
X403208Y262097D01*
G01X394346Y253822D02*
X403256Y262370D01*
G01X394083Y253798D02*
X403303Y262643D01*
G01X393820Y253771D02*
X403352Y262915D01*
G01X393555Y253746D02*
X403399Y263189D01*
G01X393322Y253749D02*
X403447Y263462D01*
G01X393094Y253757D02*
X403496Y263735D01*
G01X403543Y264008D02*
X392871Y253771D01*
G01X403591Y264282D02*
X398257Y259166D01*
G01X392660Y253795D02*
X397297Y258244D01*
G01X392450Y253821D02*
X396725Y257922D01*
G01X403639Y264555D02*
X398305Y259439D01*
G01X403687Y264828D02*
X398354Y259711D01*
G01X392248Y253853D02*
X396344Y257783D01*
G01X403734Y265100D02*
X398401Y259984D01*
G01X392052Y253893D02*
X395963Y257644D01*
G01X403782Y265374D02*
X398449Y260258D01*
G01X391857Y253933D02*
X395680Y257602D01*
G01X403808Y265625D02*
X398498Y260531D01*
G01X391671Y253984D02*
X395408Y257568D01*
G01X403827Y265871D02*
X398545Y260804D01*
G01X391491Y254037D02*
X395137Y257535D01*
G01X391310Y254091D02*
X394868Y257504D01*
G01X403847Y266117D02*
X398592Y261077D01*
G01X391141Y254156D02*
X394648Y257520D01*
G01X403867Y266364D02*
X398517Y261231D01*
G01X390974Y254224D02*
X394429Y257537D01*
G01X403888Y266612D02*
X398374Y261323D01*
G01X390807Y254291D02*
X394212Y257556D01*
G01X403889Y266840D02*
X398225Y261406D01*
G01X390651Y254368D02*
X394026Y257605D01*
G01X403862Y267040D02*
X398073Y261487D01*
G01X390498Y254449D02*
X393840Y257653D01*
G01X403835Y267242D02*
X397908Y261556D01*
G01X390346Y254530D02*
X393662Y257712D01*
G01X403806Y267443D02*
X397738Y261621D01*
G01X390201Y254618D02*
X393510Y257792D01*
G01X403779Y267643D02*
X397559Y261676D01*
G01X390064Y254712D02*
X393357Y257872D01*
G01X389924Y254807D02*
X393224Y257973D01*
G01X389791Y254907D02*
X393105Y258085D01*
G01X389668Y255014D02*
X392988Y258201D01*
G01X389543Y255122D02*
X392901Y258344D01*
G01X389421Y255233D02*
X392816Y258489D01*
G01X389311Y255355D02*
X392756Y258660D01*
G01X389203Y255477D02*
X392705Y258837D01*
G01X389093Y255600D02*
X392676Y259036D01*
G01X388998Y255735D02*
X392660Y259249D01*
G01X388903Y255872D02*
X392672Y259488D01*
G01X388809Y256009D02*
X392698Y259739D01*
G01X388726Y256157D02*
X392816Y260080D01*
G01X388649Y256310D02*
X392942Y260428D01*
G01X394108Y261547D02*
X397882Y265167D01*
G01X388572Y256463D02*
X393604Y261291D01*
G01X393643Y261328D02*
X397681Y265202D01*
G01X388501Y256623D02*
X397482Y265237D01*
G01X388442Y256793D02*
X397281Y265272D01*
G01X388382Y256963D02*
X397072Y265300D01*
G01X388328Y257138D02*
X396848Y265311D01*
G01X388287Y257326D02*
X396623Y265323D01*
G01X388248Y257514D02*
X396399Y265335D01*
G01X388210Y257705D02*
X396176Y265347D01*
G01X388191Y257915D02*
X395931Y265341D01*
G01X388172Y258124D02*
X395679Y265325D01*
G01X384196Y254538D02*
X384689Y255010D01*
G01X395425Y265310D02*
X388154Y258334D01*
G01X383712Y254300D02*
X384793Y255338D01*
G01X388160Y258567D02*
X395172Y265293D01*
G01X388165Y258799D02*
X394918Y265278D01*
G01X383326Y254157D02*
X384898Y255665D01*
G01X388172Y259033D02*
X394662Y265259D01*
G01X382954Y254027D02*
X385001Y255992D01*
G01X382646Y253958D02*
X385105Y256318D01*
G01X388204Y259292D02*
X394365Y265201D01*
G01X382337Y253890D02*
X385210Y256645D01*
G01X388238Y259551D02*
X394066Y265142D01*
G01X382029Y253822D02*
X385314Y256973D01*
G01X388282Y259821D02*
X393768Y265083D01*
G01X381771Y253801D02*
X385417Y257299D01*
G01X388368Y260131D02*
X393471Y265025D01*
G01X381513Y253782D02*
X385521Y257626D01*
G01X388455Y260441D02*
X393128Y264924D01*
G01X381256Y253763D02*
X385625Y257953D01*
G01X388543Y260752D02*
X392753Y264792D01*
G01X388630Y261063D02*
X392379Y264659D01*
G01X380998Y253741D02*
X385729Y258281D01*
G01X388865Y261516D02*
X391956Y264482D01*
G01X380784Y253763D02*
X385833Y258607D01*
G01X380569Y253784D02*
X385937Y258934D01*
G01X380354Y253806D02*
X386041Y259261D01*
G01X380140Y253828D02*
X385188Y258670D01*
G01X379946Y253868D02*
X384596Y258329D01*
G01X379771Y253928D02*
X384183Y258160D01*
G01X379596Y253986D02*
X383829Y258048D01*
G01X379419Y254046D02*
X383559Y258016D01*
G01X379246Y254104D02*
X383293Y257988D01*
G01X379097Y254188D02*
X383069Y258000D01*
G01X378955Y254281D02*
X382859Y258026D01*
G01X378813Y254373D02*
X382665Y258068D01*
G01X378673Y254465D02*
X382501Y258137D01*
G01X378532Y254557D02*
X382349Y258219D01*
G01X378417Y254675D02*
X382232Y258333D01*
G01X378307Y254797D02*
X382132Y258465D01*
G01X378197Y254918D02*
X382055Y258618D01*
G01X378087Y255040D02*
X382004Y258797D01*
G01X377978Y255162D02*
X381967Y258988D01*
G01X377895Y255310D02*
X381960Y259208D01*
G01X377816Y255461D02*
X381958Y259435D01*
G01X377736Y255611D02*
X381987Y259688D01*
G01X377656Y255762D02*
X382019Y259947D01*
G01X377576Y255913D02*
X382063Y260217D01*
G01X377527Y256093D02*
X382112Y260490D01*
G01X377478Y256273D02*
X382159Y260763D01*
G01X377430Y256454D02*
X382208Y261037D01*
G01X377381Y256635D02*
X382255Y261311D01*
G01X377339Y256821D02*
X382303Y261583D01*
G01X377325Y257034D02*
X382352Y261856D01*
G01X377310Y257247D02*
X382399Y262130D01*
G01X377295Y257461D02*
X382448Y262404D01*
G01X377280Y257674D02*
X382495Y262676D01*
G01X377290Y257910D02*
X382543Y262949D01*
G01X377314Y258161D02*
X382592Y263223D01*
G01X377340Y258413D02*
X382639Y263496D01*
G01X377364Y258663D02*
X382688Y263770D01*
G01X377398Y258922D02*
X382736Y264042D01*
G01X377446Y259195D02*
X382783Y264316D01*
G01X377493Y259469D02*
X382832Y264590D01*
G01X382879Y264863D02*
X377542Y259742D01*
G01X377590Y260015D02*
X382928Y265135D01*
G01X377637Y260288D02*
X382976Y265409D01*
G01X377686Y260562D02*
X383024Y265683D01*
G01X377733Y260835D02*
X383072Y265955D01*
G01X377781Y261107D02*
X383119Y266229D01*
G01X377828Y261381D02*
X383168Y266502D01*
G01X377877Y261654D02*
X383216Y266776D01*
G01X400551Y254095D02*
X400788D01*
G01X400078D02*
X400314D01*
G01D02*
X400551D01*
G01X399604D02*
X399842D01*
G01D02*
X400078D01*
G01X401499D02*
X401736D01*
G01D02*
X401806D01*
X401819Y254175D01*
G01X399367Y254095D02*
X399604D01*
G01X400788D02*
X401026D01*
G01X401262D02*
X401499D01*
G01X401026D02*
X401262D01*
G01X397472D02*
X397710D01*
G01X397491Y254794D02*
X397442Y254521D01*
G01X397395Y254247D02*
X397368Y254095D01*
X397472D01*
G01X397442Y254521D02*
X397395Y254247D01*
G01X398894Y254095D02*
X399130D01*
G01X398656D02*
X398894D01*
G01X399130D02*
X399367D01*
G01X397947D02*
X398183D01*
G01D02*
X398419D01*
G01D02*
X398656D01*
G01X402826Y259912D02*
X402873Y260185D01*
G01D02*
X402921Y260457D01*
G01D02*
X402968Y260730D01*
G01X402729Y259365D02*
X402777Y259638D01*
G01X402682Y259092D02*
X402729Y259365D01*
G01X402777Y259638D02*
X402826Y259912D01*
G01X402633Y258819D02*
X402682Y259092D01*
G01X403112Y261550D02*
X403161Y261823D01*
G01X401819Y254175D02*
X401868Y254449D01*
G01X403064Y261277D02*
X403112Y261550D01*
G01X402968Y260730D02*
X403017Y261004D01*
G01D02*
X403064Y261277D01*
G01X402010Y255267D02*
X402059Y255541D01*
G01X402586Y258545D02*
X402633Y258819D01*
G01X402107Y255815D02*
X402154Y256087D01*
G01X402059Y255541D02*
X402107Y255815D01*
G01X401963Y254995D02*
X402010Y255267D01*
G01X401868Y254449D02*
X401916Y254723D01*
G01D02*
X401963Y254995D01*
G01X402442Y257726D02*
X402491Y258000D01*
G01X402538Y258272D02*
X402586Y258545D01*
G01X402394Y257453D02*
X402442Y257726D01*
G01X402491Y258000D02*
X402538Y258272D01*
G01X402203Y256360D02*
X402251Y256634D01*
G01X402154Y256087D02*
X402203Y256360D01*
G01X402251Y256634D02*
X402298Y256908D01*
G01D02*
X402347Y257180D01*
G01D02*
X402394Y257453D01*
G01X397710Y254095D02*
X397947D01*
G01X398498Y260531D02*
X398449Y260258D01*
G01D02*
X398401Y259984D01*
G01X398592Y261077D02*
X398545Y260804D01*
G01D02*
X398498Y260531D01*
G01X398305Y259439D02*
X398257Y259166D01*
G01X398401Y259984D02*
X398354Y259711D01*
G01D02*
X398305Y259439D01*
G01X397539Y255068D02*
X397491Y254794D01*
G01X377493Y259469D02*
X377446Y259195D01*
G01X377925Y261927D02*
X377877Y261654D01*
G01X385417Y257299D02*
X385314Y256973D01*
G01X385521Y257626D02*
X385417Y257299D01*
G01X385314Y256973D02*
X385210Y256645D01*
G01X385625Y257953D02*
X385521Y257626D01*
G01X385210Y256645D02*
X385105Y256318D01*
G01X385729Y258281D02*
X385625Y257953D01*
G01X385105Y256318D02*
X385001Y255992D01*
G01D02*
X384898Y255665D01*
G01D02*
X384793Y255338D01*
G01X377877Y261654D02*
X377828Y261381D01*
G01X385833Y258607D02*
X385729Y258281D01*
G01X377828Y261381D02*
X377781Y261107D01*
G01X385937Y258934D02*
X385833Y258607D01*
G01X386041Y259261D02*
X385937Y258934D01*
G01X384793Y255338D02*
X384689Y255010D01*
G01X377733Y260835D02*
X377686Y260562D01*
G01D02*
X377637Y260288D01*
G01X377781Y261107D02*
X377733Y260835D01*
G01X377637Y260288D02*
X377590Y260015D01*
G01X377493Y259469D02*
X377542Y259742D01*
G01X382159Y260763D02*
X382112Y260490D01*
G01D02*
X382063Y260217D01*
G01X377590Y260015D02*
X377542Y259742D01*
G01X382208Y261037D02*
X382255Y261311D01*
G01D02*
X382303Y261583D01*
G01X377446Y259195D02*
X377398Y258922D01*
G01X382208Y261037D02*
X382159Y260763D01*
G01X382303Y261583D02*
X382352Y261856D01*
G01X403752Y267844D02*
X397373Y261724D01*
G01X403705Y268026D02*
X397178Y261765D01*
G01X403637Y268189D02*
X396974Y261798D01*
G01X403570Y268351D02*
X396767Y261825D01*
G01X403504Y268514D02*
X396551Y261844D01*
G01X403437Y268678D02*
X396329Y261859D01*
G01X403370Y268841D02*
X399264Y264902D01*
G01X399092Y264738D02*
X396102Y261870D01*
G01X403292Y268994D02*
X399313Y265176D01*
G01X398933Y264813D02*
X395872Y261875D01*
G01X398774Y264887D02*
X395638Y261878D01*
G01X403192Y269124D02*
X399360Y265449D01*
G01X398607Y264954D02*
X395366Y261844D01*
G01X403090Y269254D02*
X399389Y265704D01*
G01X398428Y265011D02*
X395092Y261810D01*
G01X402988Y269385D02*
X399410Y265951D01*
G01X394821Y261776D02*
X398251Y265066D01*
G01X402888Y269514D02*
X399389Y266157D01*
G01X394548Y261742D02*
X398073Y265123D01*
G01X402786Y269644D02*
X399364Y266362D01*
G01X402685Y269775D02*
X399306Y266533D01*
G01X402558Y269880D02*
X399248Y266705D01*
G01X402426Y269980D02*
X399159Y266847D01*
G01X402294Y270080D02*
X399069Y266986D01*
G01X402161Y270180D02*
X398957Y267107D01*
G01X402028Y270281D02*
X398834Y267217D01*
G01X401897Y270380D02*
X398704Y267319D01*
G01X401758Y270475D02*
X398552Y267399D01*
G01X401595Y270547D02*
X398397Y267479D01*
G01X401433Y270619D02*
X398220Y267536D01*
G01X401271Y270690D02*
X398035Y267586D01*
G01X401110Y270762D02*
X397841Y267627D01*
G01X400947Y270834D02*
X397621Y267644D01*
G01X400786Y270906D02*
X397403Y267662D01*
G01X400608Y270964D02*
X397168Y267663D01*
G01X400418Y271007D02*
X396927Y267658D01*
G01X400227Y271051D02*
X396684Y267654D01*
G01X400034Y271095D02*
X396433Y267640D01*
G01X399844Y271139D02*
X396178Y267622D01*
G01X399653Y271183D02*
X395921Y267603D01*
G01X399462Y271227D02*
X395647Y267567D01*
G01X399245Y271246D02*
X395373Y267532D01*
G01X399024Y271261D02*
X395076Y267473D01*
G01X389104Y261971D02*
X391407Y264181D01*
G01X398804Y271276D02*
X394774Y267411D01*
G01X398582Y271292D02*
X394441Y267319D01*
G01X394091Y267210D02*
X398361Y271307D01*
G01X393716Y267078D02*
X398139Y271322D01*
G01X393300Y266906D02*
X397913Y271331D01*
G01X392851Y266703D02*
X397669Y271324D01*
G01X392492Y266585D02*
X397425Y271318D01*
G01X392428Y266752D02*
X397181Y271311D01*
G01X392366Y266918D02*
X396932Y271300D01*
G01X392303Y267086D02*
X396672Y271276D01*
G01X392239Y267253D02*
X396410Y271253D01*
G01X392177Y267420D02*
X396148Y271230D01*
G01X392115Y267586D02*
X395870Y271189D01*
G01X392051Y267753D02*
X395587Y271144D01*
G01X391988Y267921D02*
X395302Y271099D01*
G01X391926Y268087D02*
X394994Y271031D01*
G01X391862Y268254D02*
X394682Y270958D01*
G01X391800Y268421D02*
X394359Y270876D01*
G01X387273Y266804D02*
X387266Y266798D01*
G01X387320Y267078D02*
X387028Y266798D01*
G01X387367Y267350D02*
X386792Y266798D01*
G01X387416Y267623D02*
X386556Y266798D01*
G01X387464Y267896D02*
X386319Y266798D01*
G01X387511Y268170D02*
X386082Y266798D01*
G01X387559Y268443D02*
X385846Y266798D01*
G01X387608Y268716D02*
X385608Y266798D01*
G01X387655Y268989D02*
X385371Y266798D01*
G01X387702Y269263D02*
X385134Y266798D01*
G01X387750Y269535D02*
X384898Y266798D01*
G01X387799Y269808D02*
X384662Y266798D01*
G01X387846Y270081D02*
X384424Y266798D01*
G01X387894Y270355D02*
X384187Y266798D01*
G01X387943Y270627D02*
X383949Y266798D01*
G01X387990Y270900D02*
X383713Y266798D01*
G01X387835Y270980D02*
X383476Y266798D01*
G01X383216Y266776D02*
X383239Y266798D01*
G01X387598Y270980D02*
X383239Y266798D01*
G01X377925Y261927D02*
X387362Y270980D01*
G01X387126D02*
X377972Y262200D01*
G01X386889Y270980D02*
X378021Y262474D01*
G01X386651Y270980D02*
X378068Y262747D01*
G01X386414Y270980D02*
X378116Y263020D01*
G01X386178Y270980D02*
X378165Y263292D01*
G01X385941Y270980D02*
X378212Y263566D01*
G01X385703Y270980D02*
X378260Y263840D01*
G01X385467Y270980D02*
X378308Y264113D01*
G01X385230Y270980D02*
X378356Y264385D01*
G01X384994Y270980D02*
X378403Y264659D01*
G01X384756Y270980D02*
X378452Y264932D01*
G01X384519Y270980D02*
X378500Y265205D01*
G01X384283Y270980D02*
X378547Y265478D01*
G01X384046Y270980D02*
X378596Y265751D01*
G01X378643Y266025D02*
X383979Y271144D01*
G01X384028Y271417D02*
X378691Y266298D01*
G01X384076Y271690D02*
X378740Y266570D01*
G01Y266798D02*
X384123Y271963D01*
G01X378502Y266798D02*
X384172Y272237D01*
G01X378265Y266798D02*
X384219Y272510D01*
G01X378029Y266798D02*
X384268Y272783D01*
G01X377792Y266798D02*
X384316Y273057D01*
G01X377554Y266798D02*
X384365Y273330D01*
G01X377318Y266798D02*
X384412Y273603D01*
G01X403399Y263189D02*
X403447Y263462D01*
G01X403734Y265100D02*
X403782Y265374D01*
G01X403687Y264828D02*
X403734Y265100D01*
G01X403639Y264555D02*
X403687Y264828D01*
G01X403591Y264282D02*
X403639Y264555D01*
G01X403496Y263735D02*
X403543Y264008D01*
G01X403447Y263462D02*
X403496Y263735D01*
G01X403543Y264008D02*
X403591Y264282D01*
G01X391862Y268254D02*
X391926Y268087D01*
G01X391738Y268588D02*
X391800Y268421D01*
G01X391926Y268087D02*
X391988Y267921D01*
G01X391800Y268421D02*
X391862Y268254D01*
G01X403161Y261823D02*
X403208Y262097D01*
G01X403256Y262370D02*
X403303Y262643D01*
G01D02*
X403352Y262915D01*
G01D02*
X403399Y263189D01*
G01X403208Y262097D02*
X403256Y262370D01*
G01X392428Y266752D02*
X392492Y266585D01*
G01X392366Y266918D02*
X392428Y266752D01*
G01X392051Y267753D02*
X392115Y267586D01*
G01D02*
X392177Y267420D01*
G01X391988Y267921D02*
X392051Y267753D01*
G01X392303Y267086D02*
X392366Y266918D01*
G01X392239Y267253D02*
X392303Y267086D01*
G01X392177Y267420D02*
X392239Y267253D01*
G01X399360Y265449D02*
X399313Y265176D01*
G01D02*
X399264Y264902D01*
G01X383024Y265683D02*
X383072Y265955D01*
G01D02*
X383119Y266229D01*
G01X378740Y266798D02*
X378779D01*
X378740Y266570D01*
G01X383119Y266229D02*
X383168Y266502D01*
G01X382976Y265409D02*
X383024Y265683D01*
G01X378643Y266025D02*
X378596Y265751D01*
G01X387273Y266804D02*
X387320Y267078D01*
G01X385371Y266798D02*
X385608D01*
G01X385134D02*
X385371D01*
G01X384898D02*
X384662D01*
G01X387559Y268443D02*
X387608Y268716D01*
G01X384898Y266798D02*
X385134D01*
G01X385608D02*
X385846D01*
G01X386319D02*
X386556D01*
G01X385846D02*
X386082D01*
G01D02*
X386319D01*
G01X384662D02*
X384424D01*
G01X387320Y267078D02*
X387367Y267350D01*
G01X387511Y268170D02*
X387559Y268443D01*
G01X384187Y266798D02*
X383949D01*
G01X387416Y267623D02*
X387464Y267896D01*
G01D02*
X387511Y268170D01*
G01X384424Y266798D02*
X384187D01*
G01X383949D02*
X383713D01*
G01X383476D02*
X383239D01*
G01X387367Y267350D02*
X387416Y267623D01*
G01X383713Y266798D02*
X383476D01*
G01X382736Y264042D02*
X382783Y264316D01*
G01X382879Y264863D02*
X382832Y264590D01*
G01D02*
X382783Y264316D01*
G01X382399Y262130D02*
X382448Y262404D01*
G01X382928Y265135D02*
X382976Y265409D01*
G01X387273Y266804D02*
X387271Y266798D01*
X387266D01*
G01X382352Y261856D02*
X382399Y262130D01*
G01X387028Y266798D02*
X387266D01*
G01X382879Y264863D02*
X382928Y265135D01*
G01X386792Y266798D02*
X387028D01*
G01X382639Y263496D02*
X382688Y263770D01*
G01X382448Y262404D02*
X382495Y262676D01*
G01X386556Y266798D02*
X386792D01*
G01X382592Y263223D02*
X382639Y263496D01*
G01X382495Y262676D02*
X382543Y262949D01*
G01D02*
X382592Y263223D01*
G01X382688Y263770D02*
X382736Y264042D01*
G01X378502Y266798D02*
X378740D01*
G01Y266570D02*
X378691Y266298D01*
G01D02*
X378643Y266025D01*
G01X378547Y265478D02*
X378500Y265205D01*
G01X378596Y265751D02*
X378547Y265478D01*
G01X377318Y266798D02*
X377554D01*
G01X378029D02*
X378265D01*
G01X377554D02*
X377792D01*
G01D02*
X378029D01*
G01X378500Y265205D02*
X378452Y264932D01*
G01X378021Y262474D02*
X377972Y262200D01*
G01X378116Y263020D02*
X378068Y262747D01*
G01D02*
X378021Y262474D01*
G01X383168Y266502D02*
X383216Y266776D01*
G01D02*
X383220Y266798D01*
X383239D01*
G01X377972Y262200D02*
X377925Y261927D01*
G01X378165Y263292D02*
X378116Y263020D01*
G01X378308Y264113D02*
X378260Y263840D01*
G01X378356Y264385D02*
X378308Y264113D01*
G01X378403Y264659D02*
X378356Y264385D01*
G01X378452Y264932D02*
X378403Y264659D01*
G01X378212Y263566D02*
X378165Y263292D01*
G01X378260Y263840D02*
X378212Y263566D01*
G01X378265Y266798D02*
X378502D01*
G01X403752Y267844D02*
X397373Y261724D01*
G01X403705Y268026D02*
X397178Y261765D01*
G01X403637Y268189D02*
X396974Y261798D01*
G01X403570Y268351D02*
X396767Y261825D01*
G01X403504Y268514D02*
X396551Y261844D01*
G01X403437Y268678D02*
X396329Y261859D01*
G01X403370Y268841D02*
X399264Y264902D01*
G01X399092Y264738D02*
X396102Y261870D01*
G01X403292Y268994D02*
X399313Y265176D01*
G01X398933Y264813D02*
X395872Y261875D01*
G01X398774Y264887D02*
X395638Y261878D01*
G01X403192Y269124D02*
X399360Y265449D01*
G01X398607Y264954D02*
X395366Y261844D01*
G01X403090Y269254D02*
X399389Y265704D01*
G01X398428Y265011D02*
X395092Y261810D01*
G01X402988Y269385D02*
X399410Y265951D01*
G01X394821Y261776D02*
X398251Y265066D01*
G01X402888Y269514D02*
X399389Y266157D01*
G01X394548Y261742D02*
X398073Y265123D01*
G01X402786Y269644D02*
X399364Y266362D01*
G01X402685Y269775D02*
X399306Y266533D01*
G01X402558Y269880D02*
X399248Y266705D01*
G01X402426Y269980D02*
X399159Y266847D01*
G01X402294Y270080D02*
X399069Y266986D01*
G01X402161Y270180D02*
X398957Y267107D01*
G01X402028Y270281D02*
X398834Y267217D01*
G01X401897Y270380D02*
X398704Y267319D01*
G01X401758Y270475D02*
X398552Y267399D01*
G01X401595Y270547D02*
X398397Y267479D01*
G01X401433Y270619D02*
X398220Y267536D01*
G01X401271Y270690D02*
X398035Y267586D01*
G01X401110Y270762D02*
X397841Y267627D01*
G01X400947Y270834D02*
X397621Y267644D01*
G01X400786Y270906D02*
X397403Y267662D01*
G01X400608Y270964D02*
X397168Y267663D01*
G01X400418Y271007D02*
X396927Y267658D01*
G01X400227Y271051D02*
X396684Y267654D01*
G01X400034Y271095D02*
X396433Y267640D01*
G01X399844Y271139D02*
X396178Y267622D01*
G01X399653Y271183D02*
X395921Y267603D01*
G01X399462Y271227D02*
X395647Y267567D01*
G01X399245Y271246D02*
X395373Y267532D01*
G01X399024Y271261D02*
X395076Y267473D01*
G01X389104Y261971D02*
X391407Y264181D01*
G01X398804Y271276D02*
X394774Y267411D01*
G01X398582Y271292D02*
X394441Y267319D01*
G01X394091Y267210D02*
X398361Y271307D01*
G01X393716Y267078D02*
X398139Y271322D01*
G01X393300Y266906D02*
X397913Y271331D01*
G01X392851Y266703D02*
X397669Y271324D01*
G01X392492Y266585D02*
X397425Y271318D01*
G01X392428Y266752D02*
X397181Y271311D01*
G01X392366Y266918D02*
X396932Y271300D01*
G01X392303Y267086D02*
X396672Y271276D01*
G01X392239Y267253D02*
X396410Y271253D01*
G01X392177Y267420D02*
X396148Y271230D01*
G01X392115Y267586D02*
X395870Y271189D01*
G01X392051Y267753D02*
X395587Y271144D01*
G01X391988Y267921D02*
X395302Y271099D01*
G01X391926Y268087D02*
X394994Y271031D01*
G01X391862Y268254D02*
X394682Y270958D01*
G01X391800Y268421D02*
X394359Y270876D01*
G01X387273Y266804D02*
X387266Y266798D01*
G01X387320Y267078D02*
X387028Y266798D01*
G01X387367Y267350D02*
X386792Y266798D01*
G01X387416Y267623D02*
X386556Y266798D01*
G01X387464Y267896D02*
X386319Y266798D01*
G01X387511Y268170D02*
X386082Y266798D01*
G01X387559Y268443D02*
X385846Y266798D01*
G01X387608Y268716D02*
X385608Y266798D01*
G01X387655Y268989D02*
X385371Y266798D01*
G01X387702Y269263D02*
X385134Y266798D01*
G01X387750Y269535D02*
X384898Y266798D01*
G01X387799Y269808D02*
X384662Y266798D01*
G01X387846Y270081D02*
X384424Y266798D01*
G01X387894Y270355D02*
X384187Y266798D01*
G01X387943Y270627D02*
X383949Y266798D01*
G01X387990Y270900D02*
X383713Y266798D01*
G01X387835Y270980D02*
X383476Y266798D01*
G01X383216Y266776D02*
X383239Y266798D01*
G01X387598Y270980D02*
X383239Y266798D01*
G01X377925Y261927D02*
X387362Y270980D01*
G01X387126D02*
X377972Y262200D01*
G01X386889Y270980D02*
X378021Y262474D01*
G01X386651Y270980D02*
X378068Y262747D01*
G01X386414Y270980D02*
X378116Y263020D01*
G01X386178Y270980D02*
X378165Y263292D01*
G01X385941Y270980D02*
X378212Y263566D01*
G01X385703Y270980D02*
X378260Y263840D01*
G01X385467Y270980D02*
X378308Y264113D01*
G01X385230Y270980D02*
X378356Y264385D01*
G01X384994Y270980D02*
X378403Y264659D01*
G01X384756Y270980D02*
X378452Y264932D01*
G01X384519Y270980D02*
X378500Y265205D01*
G01X384283Y270980D02*
X378547Y265478D01*
G01X384046Y270980D02*
X378596Y265751D01*
G01X378643Y266025D02*
X383979Y271144D01*
G01X384028Y271417D02*
X378691Y266298D01*
G01X384076Y271690D02*
X378740Y266570D01*
G01Y266798D02*
X384123Y271963D01*
G01X378502Y266798D02*
X384172Y272237D01*
G01X378265Y266798D02*
X384219Y272510D01*
G01X378029Y266798D02*
X384268Y272783D01*
G01X377792Y266798D02*
X384316Y273057D01*
G01X377554Y266798D02*
X384365Y273330D01*
G01X377318Y266798D02*
X384412Y273603D01*
G01X403399Y263189D02*
X403447Y263462D01*
G01X403734Y265100D02*
X403782Y265374D01*
G01X403687Y264828D02*
X403734Y265100D01*
G01X403639Y264555D02*
X403687Y264828D01*
G01X403591Y264282D02*
X403639Y264555D01*
G01X403496Y263735D02*
X403543Y264008D01*
G01X403447Y263462D02*
X403496Y263735D01*
G01X403543Y264008D02*
X403591Y264282D01*
G01X391862Y268254D02*
X391926Y268087D01*
G01X391738Y268588D02*
X391800Y268421D01*
G01X391926Y268087D02*
X391988Y267921D01*
G01X391800Y268421D02*
X391862Y268254D01*
G01X403161Y261823D02*
X403208Y262097D01*
G01X403256Y262370D02*
X403303Y262643D01*
G01D02*
X403352Y262915D01*
G01D02*
X403399Y263189D01*
G01X403208Y262097D02*
X403256Y262370D01*
G01X392428Y266752D02*
X392492Y266585D01*
G01X392366Y266918D02*
X392428Y266752D01*
G01X392051Y267753D02*
X392115Y267586D01*
G01D02*
X392177Y267420D01*
G01X391988Y267921D02*
X392051Y267753D01*
G01X392303Y267086D02*
X392366Y266918D01*
G01X392239Y267253D02*
X392303Y267086D01*
G01X392177Y267420D02*
X392239Y267253D01*
G01X399360Y265449D02*
X399313Y265176D01*
G01D02*
X399264Y264902D01*
G01X383024Y265683D02*
X383072Y265955D01*
G01D02*
X383119Y266229D01*
G01X378740Y266798D02*
X378779D01*
X378740Y266570D01*
G01X383119Y266229D02*
X383168Y266502D01*
G01X382976Y265409D02*
X383024Y265683D01*
G01X378643Y266025D02*
X378596Y265751D01*
G01X387273Y266804D02*
X387320Y267078D01*
G01X385371Y266798D02*
X385608D01*
G01X385134D02*
X385371D01*
G01X384898D02*
X384662D01*
G01X387559Y268443D02*
X387608Y268716D01*
G01X384898Y266798D02*
X385134D01*
G01X385608D02*
X385846D01*
G01X386319D02*
X386556D01*
G01X385846D02*
X386082D01*
G01D02*
X386319D01*
G01X384662D02*
X384424D01*
G01X387320Y267078D02*
X387367Y267350D01*
G01X387511Y268170D02*
X387559Y268443D01*
G01X384187Y266798D02*
X383949D01*
G01X387416Y267623D02*
X387464Y267896D01*
G01D02*
X387511Y268170D01*
G01X384424Y266798D02*
X384187D01*
G01X383949D02*
X383713D01*
G01X383476D02*
X383239D01*
G01X387367Y267350D02*
X387416Y267623D01*
G01X383713Y266798D02*
X383476D01*
G01X382736Y264042D02*
X382783Y264316D01*
G01X382879Y264863D02*
X382832Y264590D01*
G01D02*
X382783Y264316D01*
G01X382399Y262130D02*
X382448Y262404D01*
G01X382928Y265135D02*
X382976Y265409D01*
G01X387273Y266804D02*
X387271Y266798D01*
X387266D01*
G01X382352Y261856D02*
X382399Y262130D01*
G01X387028Y266798D02*
X387266D01*
G01X382879Y264863D02*
X382928Y265135D01*
G01X386792Y266798D02*
X387028D01*
G01X382639Y263496D02*
X382688Y263770D01*
G01X382448Y262404D02*
X382495Y262676D01*
G01X386556Y266798D02*
X386792D01*
G01X382592Y263223D02*
X382639Y263496D01*
G01X382495Y262676D02*
X382543Y262949D01*
G01D02*
X382592Y263223D01*
G01X382688Y263770D02*
X382736Y264042D01*
G01X378502Y266798D02*
X378740D01*
G01Y266570D02*
X378691Y266298D01*
G01D02*
X378643Y266025D01*
G01X378547Y265478D02*
X378500Y265205D01*
G01X378596Y265751D02*
X378547Y265478D01*
G01X377318Y266798D02*
X377554D01*
G01X378029D02*
X378265D01*
G01X377554D02*
X377792D01*
G01D02*
X378029D01*
G01X378500Y265205D02*
X378452Y264932D01*
G01X378021Y262474D02*
X377972Y262200D01*
G01X378116Y263020D02*
X378068Y262747D01*
G01D02*
X378021Y262474D01*
G01X383168Y266502D02*
X383216Y266776D01*
G01D02*
X383220Y266798D01*
X383239D01*
G01X377972Y262200D02*
X377925Y261927D01*
G01X378165Y263292D02*
X378116Y263020D01*
G01X378308Y264113D02*
X378260Y263840D01*
G01X378356Y264385D02*
X378308Y264113D01*
G01X378403Y264659D02*
X378356Y264385D01*
G01X378452Y264932D02*
X378403Y264659D01*
G01X378212Y263566D02*
X378165Y263292D01*
G01X378260Y263840D02*
X378212Y263566D01*
G01X378265Y266798D02*
X378502D01*
G01X391738Y268588D02*
X394008Y270767D01*
G01X391674Y268755D02*
X393657Y270657D01*
G01X391611Y268922D02*
X393263Y270506D01*
G01X391549Y269089D02*
X392863Y270349D01*
G01X391485Y269256D02*
X392417Y270150D01*
G01X391423Y269423D02*
X391955Y269933D01*
G01X391361Y269589D02*
X391460Y269685D01*
G01X384892Y276336D02*
X379552Y271214D01*
G01X384940Y276609D02*
X379601Y271487D01*
G01X384988Y276883D02*
X379649Y271761D01*
G01X385036Y277155D02*
X379696Y272033D01*
G01X385085Y277429D02*
X379745Y272307D01*
G01X384834Y277416D02*
X379792Y272580D01*
G01X384379Y277208D02*
X379841Y272853D01*
G01X383926Y276999D02*
X379889Y273126D01*
G01X383471Y276790D02*
X379936Y273400D01*
G01X383015Y276581D02*
X379985Y273674D01*
G01X382561Y276372D02*
X380032Y273946D01*
G01X382108Y276163D02*
X380080Y274219D01*
G01X381652Y275954D02*
X380129Y274493D01*
G01X381196Y275745D02*
X380176Y274766D01*
G01X380743Y275537D02*
X380225Y275039D01*
G01X380289Y275328D02*
X380272Y275312D01*
G01X391674Y268755D02*
X391738Y268588D01*
G01X391611Y268922D02*
X391674Y268755D01*
G01X391549Y269089D02*
X391611Y268922D01*
G01X391485Y269256D02*
X391549Y269089D01*
G01X391361Y269589D02*
X391423Y269423D01*
G01D02*
X391485Y269256D01*
G01X378835Y270980D02*
X378599D01*
G01X379072D02*
X378835D01*
G01X379308D02*
X379072D01*
G01X387702Y269263D02*
X387750Y269535D01*
G01D02*
X387799Y269808D01*
G01X387608Y268716D02*
X387655Y268989D01*
G01D02*
X387702Y269263D01*
G01X387894Y270355D02*
X387943Y270627D01*
G01X387846Y270081D02*
X387894Y270355D01*
G01X387943Y270627D02*
X387990Y270900D01*
G01X387799Y269808D02*
X387846Y270081D01*
G01X385230Y270980D02*
X384994D01*
G01X385467D02*
X385230D01*
G01X385941D02*
X385703D01*
G01D02*
X385467D01*
G01X386414D02*
X386178D01*
G01D02*
X385941D01*
G01X384519D02*
X384283D01*
G01X384076Y271690D02*
X384123Y271963D01*
G01D02*
X384172Y272237D01*
G01X386651Y270980D02*
X386414D01*
G01X384994D02*
X384756D01*
G01D02*
X384519D01*
G01X383979Y271144D02*
X384028Y271417D01*
G01D02*
X384076Y271690D01*
G01X384283Y270980D02*
X384046D01*
G01X387990Y270900D02*
X388004Y270980D01*
X387835D01*
G01X387362D02*
X387126D01*
G01X386889D02*
X386651D01*
G01X387126D02*
X386889D01*
G01X387835D02*
X387598D01*
G01D02*
X387362D01*
G01X383979Y271144D02*
X383951Y270980D01*
X384046D01*
G01X380129Y274493D02*
X380080Y274219D01*
G01X380129Y274493D02*
X380176Y274766D01*
G01X379985Y273674D02*
X379936Y273400D01*
G01X380080Y274219D02*
X380032Y273946D01*
G01X379936Y273400D02*
X379889Y273126D01*
G01X380176Y274766D02*
X380225Y275039D01*
G01X380032Y273946D02*
X379985Y273674D01*
G01X380289Y275328D02*
X380274Y275321D01*
X380272Y275312D01*
G01X380225Y275039D02*
X380272Y275312D01*
G01X379889Y273126D02*
X379841Y272853D01*
G01X379745Y272307D02*
X379696Y272033D01*
G01X379792Y272580D02*
X379745Y272307D01*
G01X379841Y272853D02*
X379792Y272580D01*
G01X379601Y271487D02*
X379552Y271214D01*
G01X379308Y270980D02*
X379512D01*
X379552Y271214D01*
G01X379649Y271761D02*
X379601Y271487D01*
G01X379696Y272033D02*
X379649Y271761D01*
G01X384834Y277416D02*
X384379Y277208D01*
G01X384652Y274969D02*
X384700Y275243D01*
G01X384379Y277208D02*
X383926Y276999D01*
G01X378361Y270980D02*
X378124D01*
G01X378599D02*
X378361D01*
G01X383471Y276790D02*
X383015Y276581D01*
G01X383926Y276999D02*
X383471Y276790D01*
G01X385085Y277429D02*
X385104Y277541D01*
X384834Y277416D01*
G01X384748Y275517D02*
X384796Y275790D01*
G01D02*
X384845Y276062D01*
G01X384700Y275243D02*
X384748Y275517D01*
G01X384988Y276883D02*
X385036Y277155D01*
G01X384940Y276609D02*
X384988Y276883D01*
G01X384845Y276062D02*
X384892Y276336D01*
G01D02*
X384940Y276609D01*
G01X385036Y277155D02*
X385085Y277429D01*
G01X381652Y275954D02*
X381196Y275745D01*
G01X383015Y276581D02*
X382561Y276372D01*
G01X380743Y275537D02*
X380289Y275328D01*
G01X381196Y275745D02*
X380743Y275537D01*
G01X377888Y270980D02*
X377651D01*
G01X382561Y276372D02*
X382108Y276163D01*
G01X378124Y270980D02*
X377888D01*
G01X384172Y272237D02*
X384219Y272510D01*
G01X377177Y270980D02*
X377413D01*
G01D02*
X377651D01*
G01X382108Y276163D02*
X381652Y275954D01*
G01X384556Y274424D02*
X384603Y274696D01*
G01X384365Y273330D02*
X384412Y273603D01*
G01X384219Y272510D02*
X384268Y272783D01*
G01X384508Y274150D02*
X384556Y274424D01*
G01X384412Y273603D02*
X384459Y273876D01*
G01X384603Y274696D02*
X384652Y274969D01*
G01X384268Y272783D02*
X384316Y273057D01*
G01X384459Y273876D02*
X384508Y274150D01*
G01X384316Y273057D02*
X384365Y273330D01*
G01X391738Y268588D02*
X394008Y270767D01*
G01X391674Y268755D02*
X393657Y270657D01*
G01X391611Y268922D02*
X393263Y270506D01*
G01X391549Y269089D02*
X392863Y270349D01*
G01X391485Y269256D02*
X392417Y270150D01*
G01X391423Y269423D02*
X391955Y269933D01*
G01X391361Y269589D02*
X391460Y269685D01*
G01X384892Y276336D02*
X379552Y271214D01*
G01X384940Y276609D02*
X379601Y271487D01*
G01X384988Y276883D02*
X379649Y271761D01*
G01X385036Y277155D02*
X379696Y272033D01*
G01X385085Y277429D02*
X379745Y272307D01*
G01X384834Y277416D02*
X379792Y272580D01*
G01X384379Y277208D02*
X379841Y272853D01*
G01X383926Y276999D02*
X379889Y273126D01*
G01X383471Y276790D02*
X379936Y273400D01*
G01X383015Y276581D02*
X379985Y273674D01*
G01X382561Y276372D02*
X380032Y273946D01*
G01X382108Y276163D02*
X380080Y274219D01*
G01X381652Y275954D02*
X380129Y274493D01*
G01X381196Y275745D02*
X380176Y274766D01*
G01X380743Y275537D02*
X380225Y275039D01*
G01X380289Y275328D02*
X380272Y275312D01*
G01X391674Y268755D02*
X391738Y268588D01*
G01X391611Y268922D02*
X391674Y268755D01*
G01X391549Y269089D02*
X391611Y268922D01*
G01X391485Y269256D02*
X391549Y269089D01*
G01X391361Y269589D02*
X391423Y269423D01*
G01D02*
X391485Y269256D01*
G01X378835Y270980D02*
X378599D01*
G01X379072D02*
X378835D01*
G01X379308D02*
X379072D01*
G01X387702Y269263D02*
X387750Y269535D01*
G01D02*
X387799Y269808D01*
G01X387608Y268716D02*
X387655Y268989D01*
G01D02*
X387702Y269263D01*
G01X387894Y270355D02*
X387943Y270627D01*
G01X387846Y270081D02*
X387894Y270355D01*
G01X387943Y270627D02*
X387990Y270900D01*
G01X387799Y269808D02*
X387846Y270081D01*
G01X385230Y270980D02*
X384994D01*
G01X385467D02*
X385230D01*
G01X385941D02*
X385703D01*
G01D02*
X385467D01*
G01X386414D02*
X386178D01*
G01D02*
X385941D01*
G01X384519D02*
X384283D01*
G01X384076Y271690D02*
X384123Y271963D01*
G01D02*
X384172Y272237D01*
G01X386651Y270980D02*
X386414D01*
G01X384994D02*
X384756D01*
G01D02*
X384519D01*
G01X383979Y271144D02*
X384028Y271417D01*
G01D02*
X384076Y271690D01*
G01X384283Y270980D02*
X384046D01*
G01X387990Y270900D02*
X388004Y270980D01*
X387835D01*
G01X387362D02*
X387126D01*
G01X386889D02*
X386651D01*
G01X387126D02*
X386889D01*
G01X387835D02*
X387598D01*
G01D02*
X387362D01*
G01X383979Y271144D02*
X383951Y270980D01*
X384046D01*
G01X380129Y274493D02*
X380080Y274219D01*
G01X380129Y274493D02*
X380176Y274766D01*
G01X379985Y273674D02*
X379936Y273400D01*
G01X380080Y274219D02*
X380032Y273946D01*
G01X379936Y273400D02*
X379889Y273126D01*
G01X380176Y274766D02*
X380225Y275039D01*
G01X380032Y273946D02*
X379985Y273674D01*
G01X380289Y275328D02*
X380274Y275321D01*
X380272Y275312D01*
G01X380225Y275039D02*
X380272Y275312D01*
G01X379889Y273126D02*
X379841Y272853D01*
G01X379745Y272307D02*
X379696Y272033D01*
G01X379792Y272580D02*
X379745Y272307D01*
G01X379841Y272853D02*
X379792Y272580D01*
G01X379601Y271487D02*
X379552Y271214D01*
G01X379308Y270980D02*
X379512D01*
X379552Y271214D01*
G01X379649Y271761D02*
X379601Y271487D01*
G01X379696Y272033D02*
X379649Y271761D01*
G01X384834Y277416D02*
X384379Y277208D01*
G01X384652Y274969D02*
X384700Y275243D01*
G01X384379Y277208D02*
X383926Y276999D01*
G01X378361Y270980D02*
X378124D01*
G01X378599D02*
X378361D01*
G01X383471Y276790D02*
X383015Y276581D01*
G01X383926Y276999D02*
X383471Y276790D01*
G01X385085Y277429D02*
X385104Y277541D01*
X384834Y277416D01*
G01X384748Y275517D02*
X384796Y275790D01*
G01D02*
X384845Y276062D01*
G01X384700Y275243D02*
X384748Y275517D01*
G01X384988Y276883D02*
X385036Y277155D01*
G01X384940Y276609D02*
X384988Y276883D01*
G01X384845Y276062D02*
X384892Y276336D01*
G01D02*
X384940Y276609D01*
G01X385036Y277155D02*
X385085Y277429D01*
G01X381652Y275954D02*
X381196Y275745D01*
G01X383015Y276581D02*
X382561Y276372D01*
G01X380743Y275537D02*
X380289Y275328D01*
G01X381196Y275745D02*
X380743Y275537D01*
G01X377888Y270980D02*
X377651D01*
G01X382561Y276372D02*
X382108Y276163D01*
G01X378124Y270980D02*
X377888D01*
G01X384172Y272237D02*
X384219Y272510D01*
G01X377177Y270980D02*
X377413D01*
G01D02*
X377651D01*
G01X382108Y276163D02*
X381652Y275954D01*
G01X384556Y274424D02*
X384603Y274696D01*
G01X384365Y273330D02*
X384412Y273603D01*
G01X384219Y272510D02*
X384268Y272783D01*
G01X384508Y274150D02*
X384556Y274424D01*
G01X384412Y273603D02*
X384459Y273876D01*
G01X384603Y274696D02*
X384652Y274969D01*
G01X384268Y272783D02*
X384316Y273057D01*
G01X384459Y273876D02*
X384508Y274150D01*
G01X384316Y273057D02*
X384365Y273330D01*
G01X387795Y344488D02*
Y350535D01*
G03X385373Y358928I-15748J1D01*
G02X402029I8328J5245D01*
G03X399606Y350535I13326J-8393D01*
G01Y344488D01*
G02X387795I-5905J0D01*
G01Y350535D02*
G03X385373Y358928I-15748J1D01*
G02X402029I8328J5245D01*
G03X399606Y350535I13326J-8393D01*
G01Y344488D01*
G02X387795I-5905J0D01*
G01Y350535D01*
G01X452000Y-1045000D02*
Y-1070000D01*
G01X454633Y-1047500D02*
Y-1052500D01*
X457167D01*
G01X460240Y-1047500D02*
X461760D01*
G01X461000D02*
Y-1052500D01*
G01X460240D02*
X461760D01*
G01X466607Y-1049833D02*
X466860Y-1049583D01*
X467050Y-1049167D01*
X467177Y-1048583D01*
X467050Y-1048083D01*
X466797Y-1047750D01*
X466353Y-1047500D01*
X464643D01*
Y-1052500D01*
X466733D01*
X467177Y-1052167D01*
X467430Y-1051667D01*
X467557Y-1051083D01*
X467430Y-1050500D01*
X467050Y-1050000D01*
X466607Y-1049833D01*
X464643D01*
G01X471200Y-1052667D02*
X471073Y-1052583D01*
Y-1052417D01*
X471200Y-1052333D01*
X471327Y-1052417D01*
Y-1052583D01*
X471200Y-1052667D01*
G01Y-1050417D02*
X471073Y-1050333D01*
Y-1050167D01*
X471200Y-1050083D01*
X471327Y-1050167D01*
Y-1050333D01*
X471200Y-1050417D01*
G01X495000Y-1045000D02*
Y-1070000D01*
G01X498900Y-1047500D02*
Y-1052500D01*
G01X497443Y-1047500D02*
X500357D01*
G01X504000Y-1052500D02*
X503620Y-1052417D01*
X503240Y-1052083D01*
X502987Y-1051500D01*
X502860Y-1050833D01*
X502987Y-1050167D01*
X503240Y-1049583D01*
X503620Y-1049250D01*
X504000Y-1049167D01*
X504380Y-1049250D01*
X504760Y-1049583D01*
X505013Y-1050167D01*
X505077Y-1050833D01*
X505013Y-1051500D01*
X504760Y-1052083D01*
X504380Y-1052417D01*
X504000Y-1052500D01*
G01X509100D02*
X508720Y-1052417D01*
X508340Y-1052083D01*
X508087Y-1051500D01*
X507960Y-1050833D01*
X508087Y-1050167D01*
X508340Y-1049583D01*
X508720Y-1049250D01*
X509100Y-1049167D01*
X509480Y-1049250D01*
X509860Y-1049583D01*
X510113Y-1050167D01*
X510177Y-1050833D01*
X510113Y-1051500D01*
X509860Y-1052083D01*
X509480Y-1052417D01*
X509100Y-1052500D01*
G01X514200D02*
Y-1047500D01*
G01X519300Y-1052667D02*
X519173Y-1052583D01*
Y-1052417D01*
X519300Y-1052333D01*
X519427Y-1052417D01*
Y-1052583D01*
X519300Y-1052667D01*
G01Y-1050417D02*
X519173Y-1050333D01*
Y-1050167D01*
X519300Y-1050083D01*
X519427Y-1050167D01*
Y-1050333D01*
X519300Y-1050417D01*
G01X495000Y-1020000D02*
Y-1045000D01*
G01X497633Y-1027500D02*
Y-1022500D01*
X499217D01*
X499723Y-1022750D01*
X500040Y-1023083D01*
X500167Y-1023750D01*
X500040Y-1024417D01*
X499660Y-1024833D01*
X499217Y-1025083D01*
X497633D01*
G01X499217D02*
X500167Y-1027500D01*
G01X505267D02*
X502733D01*
Y-1022500D01*
X505267D01*
G01X504253Y-1024917D02*
X502733D01*
G01X507517Y-1022500D02*
X509100Y-1027500D01*
X510683Y-1022500D01*
G01X514200Y-1027667D02*
X514073Y-1027583D01*
Y-1027417D01*
X514200Y-1027333D01*
X514327Y-1027417D01*
Y-1027583D01*
X514200Y-1027667D01*
G01Y-1025417D02*
X514073Y-1025333D01*
Y-1025167D01*
X514200Y-1025083D01*
X514327Y-1025167D01*
Y-1025333D01*
X514200Y-1025417D01*
G01X503013Y-1073167D02*
X503120Y-1073042D01*
X503200Y-1072833D01*
X503253Y-1072542D01*
X503200Y-1072292D01*
X503093Y-1072125D01*
X502907Y-1072000D01*
X502187D01*
Y-1074500D01*
X503067D01*
X503253Y-1074333D01*
X503360Y-1074083D01*
X503413Y-1073792D01*
X503360Y-1073500D01*
X503200Y-1073250D01*
X503013Y-1073167D01*
X502187D01*
G01X505480Y-1074500D02*
Y-1072833D01*
G01Y-1073125D02*
X505373Y-1072958D01*
X505213Y-1072875D01*
X505027Y-1072833D01*
X504840Y-1072917D01*
X504680Y-1073083D01*
X504573Y-1073333D01*
X504520Y-1073667D01*
X504573Y-1074000D01*
X504680Y-1074250D01*
X504840Y-1074417D01*
X505027Y-1074500D01*
X505213Y-1074458D01*
X505373Y-1074333D01*
X505480Y-1074167D01*
G01X506800Y-1074208D02*
X506933Y-1074375D01*
X507120Y-1074500D01*
X507280D01*
X507440Y-1074417D01*
X507547Y-1074292D01*
X507600Y-1074125D01*
X507573Y-1073875D01*
X507467Y-1073750D01*
X506987Y-1073500D01*
X506880Y-1073208D01*
X506933Y-1073000D01*
X507040Y-1072875D01*
X507200Y-1072833D01*
X507360Y-1072875D01*
X507520Y-1073000D01*
G01X509000Y-1073375D02*
X509853D01*
X509773Y-1073083D01*
X509640Y-1072917D01*
X509453Y-1072833D01*
X509267Y-1072875D01*
X509107Y-1073000D01*
X509000Y-1073292D01*
X508947Y-1073542D01*
Y-1073792D01*
X509000Y-1074042D01*
X509133Y-1074292D01*
X509293Y-1074458D01*
X509480Y-1074500D01*
X509667Y-1074417D01*
X509853Y-1074167D01*
G01X511120Y-1074500D02*
Y-1072000D01*
G01Y-1073250D02*
X511253Y-1073000D01*
X511413Y-1072875D01*
X511573Y-1072833D01*
X511813Y-1072917D01*
X511973Y-1073083D01*
X512080Y-1073375D01*
Y-1073708D01*
X512027Y-1074042D01*
X511920Y-1074292D01*
X511733Y-1074458D01*
X511573Y-1074500D01*
X511413Y-1074458D01*
X511253Y-1074333D01*
X511120Y-1074125D01*
G01X513800Y-1074500D02*
X513640Y-1074458D01*
X513480Y-1074292D01*
X513373Y-1074000D01*
X513320Y-1073667D01*
X513373Y-1073333D01*
X513480Y-1073042D01*
X513640Y-1072875D01*
X513800Y-1072833D01*
X513960Y-1072875D01*
X514120Y-1073042D01*
X514227Y-1073333D01*
X514253Y-1073667D01*
X514227Y-1074000D01*
X514120Y-1074292D01*
X513960Y-1074458D01*
X513800Y-1074500D01*
G01X516480D02*
Y-1072833D01*
G01Y-1073125D02*
X516373Y-1072958D01*
X516213Y-1072875D01*
X516027Y-1072833D01*
X515840Y-1072917D01*
X515680Y-1073083D01*
X515573Y-1073333D01*
X515520Y-1073667D01*
X515573Y-1074000D01*
X515680Y-1074250D01*
X515840Y-1074417D01*
X516027Y-1074500D01*
X516213Y-1074458D01*
X516373Y-1074333D01*
X516480Y-1074167D01*
G01X517827Y-1074500D02*
Y-1072833D01*
G01Y-1073167D02*
X517960Y-1073000D01*
X518093Y-1072875D01*
X518280Y-1072833D01*
X518413Y-1072875D01*
X518573Y-1073000D01*
G01X520880Y-1072000D02*
Y-1074500D01*
G01Y-1074125D02*
X520773Y-1074333D01*
X520613Y-1074458D01*
X520427Y-1074500D01*
X520213Y-1074417D01*
X520053Y-1074208D01*
X519947Y-1073958D01*
X519920Y-1073667D01*
X519947Y-1073375D01*
X520053Y-1073125D01*
X520213Y-1072917D01*
X520427Y-1072833D01*
X520613Y-1072875D01*
X520747Y-1072958D01*
X520880Y-1073125D01*
G01X524267Y-1074500D02*
Y-1072000D01*
X524933D01*
X525147Y-1072125D01*
X525280Y-1072292D01*
X525333Y-1072625D01*
X525280Y-1072958D01*
X525120Y-1073167D01*
X524933Y-1073292D01*
X524267D01*
G01X524933D02*
X525333Y-1074500D01*
G01X526600Y-1073375D02*
X527453D01*
X527373Y-1073083D01*
X527240Y-1072917D01*
X527053Y-1072833D01*
X526867Y-1072875D01*
X526707Y-1073000D01*
X526600Y-1073292D01*
X526547Y-1073542D01*
Y-1073792D01*
X526600Y-1074042D01*
X526733Y-1074292D01*
X526893Y-1074458D01*
X527080Y-1074500D01*
X527267Y-1074417D01*
X527453Y-1074167D01*
G01X528720Y-1072833D02*
X529200Y-1074500D01*
X529680Y-1072833D01*
G01X531400Y-1074583D02*
X531347Y-1074542D01*
Y-1074458D01*
X531400Y-1074417D01*
X531453Y-1074458D01*
Y-1074542D01*
X531400Y-1074583D01*
G01X533600Y-1074500D02*
X533787Y-1074458D01*
X534000Y-1074333D01*
X534133Y-1074125D01*
X534187Y-1073833D01*
X534133Y-1073542D01*
X533973Y-1073292D01*
X533733Y-1073167D01*
X533467D01*
X533307Y-1073083D01*
X533173Y-1072875D01*
X533120Y-1072583D01*
X533200Y-1072292D01*
X533387Y-1072083D01*
X533600Y-1072000D01*
X533813Y-1072083D01*
X534000Y-1072292D01*
X534080Y-1072583D01*
X534027Y-1072875D01*
X533893Y-1073083D01*
X533733Y-1073167D01*
X533467D01*
X533227Y-1073292D01*
X533067Y-1073542D01*
X533013Y-1073833D01*
X533067Y-1074125D01*
X533200Y-1074333D01*
X533413Y-1074458D01*
X533600Y-1074500D01*
G01X536013Y-1073167D02*
X536120Y-1073042D01*
X536200Y-1072833D01*
X536253Y-1072542D01*
X536200Y-1072292D01*
X536093Y-1072125D01*
X535907Y-1072000D01*
X535187D01*
Y-1074500D01*
X536067D01*
X536253Y-1074333D01*
X536360Y-1074083D01*
X536413Y-1073792D01*
X536360Y-1073500D01*
X536200Y-1073250D01*
X536013Y-1073167D01*
X535187D01*
G01X742126Y64961D02*
Y71007D01*
G03X739703Y79400I-15749J0D01*
G02X756360I8329J5246D01*
G03X753937Y71007I13326J-8393D01*
G01Y64961D01*
G02X742126I-5905J0D01*
G01Y71007D02*
G03X739703Y79400I-15749J0D01*
G02X756360I8329J5246D01*
G03X753937Y71007I13326J-8393D01*
G01Y64961D01*
G02X742126I-5905J0D01*
G01Y71007D01*
G01X753937Y344488D02*
G02X742126I-5905J0D01*
G01Y350535D01*
G03X739703Y358928I-15749J0D01*
G02X756360I8329J5246D01*
G03X753937Y350535I13326J-8393D01*
G01Y344488D01*
G01X742126D02*
Y350535D01*
G03X739703Y358928I-15749J0D01*
G02X756360I8329J5246D01*
G03X753937Y350535I13326J-8393D01*
G01Y344488D01*
G02X742126I-5905J0D01*
G01X813780Y88465D02*
G02X830394I8307J0D01*
G02X813780I-8307J0D01*
G01D02*
G02X830394I8307J0D01*
G02X813780I-8307J0D01*
G01Y313504D02*
G02X830394I8307J0D01*
G02X813780I-8307J0D01*
G01D02*
G02X830394I8307J0D01*
G02X813780I-8307J0D01*
G01X931890Y88465D02*
G02X948504I8307J0D01*
G02X931890I-8307J0D01*
G01D02*
G02X948504I8307J0D01*
G02X931890I-8307J0D01*
G01Y313504D02*
G02X948504I8307J0D01*
G02X931890I-8307J0D01*
G01D02*
G02X948504I8307J0D01*
G02X931890I-8307J0D01*
G01X978346Y64961D02*
Y71007D01*
G03X975924Y79400I-15748J1D01*
G02X992580I8328J5245D01*
G03X990157Y71007I13326J-8393D01*
G01Y64961D01*
G02X978346I-5906J0D01*
G01Y71007D02*
G03X975924Y79400I-15748J1D01*
G02X992580I8328J5245D01*
G03X990157Y71007I13326J-8393D01*
G01Y64961D01*
G02X978346I-5906J0D01*
G01Y71007D01*
G01Y344488D02*
Y350535D01*
G03X975924Y358928I-15748J1D01*
G02X992580I8328J5245D01*
G03X990157Y350535I13326J-8393D01*
G01Y344488D01*
G02X978346I-5906J0D01*
G01Y350535D02*
G03X975924Y358928I-15748J1D01*
G02X992580I8328J5245D01*
G03X990157Y350535I13326J-8393D01*
G01Y344488D01*
G02X978346I-5906J0D01*
G01Y350535D01*
G01X1344488Y344488D02*
G02X1332677I-5905J0D01*
G01Y350535D01*
G03X1330254Y358928I-15749J0D01*
G02X1346911I8329J5246D01*
G03X1344488Y350535I13326J-8393D01*
G01Y344488D01*
G01X1332677D02*
Y350535D01*
G03X1330254Y358928I-15749J0D01*
G02X1346911I8329J5246D01*
G03X1344488Y350535I13326J-8393D01*
G01Y344488D01*
G02X1332677I-5905J0D01*
G01X1426693Y15512D02*
G02X1436142I4724J0D01*
G02X1426693I-4725J0D01*
G01D02*
G02X1436142I4724J0D01*
G02X1426693I-4725J0D01*
G01X1423228Y561024D02*
G02X1411417I-5906J0D01*
G01Y567070D01*
G03X1408995Y575463I-15748J1D01*
G02X1425651I8328J5245D01*
G03X1423228Y567070I13326J-8393D01*
G01Y561024D01*
G01X1411417D02*
Y567070D01*
G03X1408995Y575463I-15748J1D01*
G02X1425651I8328J5245D01*
G03X1423228Y567070I13326J-8393D01*
G01Y561024D01*
G02X1411417I-5906J0D01*
G01X1446850Y53150D02*
Y59196D01*
G03X1444428Y67589I-15748J1D01*
G02X1461084I8328J5245D01*
G03X1458661Y59196I13326J-8393D01*
G01Y53150D01*
G02X1446850I-5905J0D01*
G01Y59196D02*
G03X1444428Y67589I-15748J1D01*
G02X1461084I8328J5245D01*
G03X1458661Y59196I13326J-8393D01*
G01Y53150D01*
G02X1446850I-5905J0D01*
G01Y59196D01*
G01X1464370Y628465D02*
G02X1472638I4134J0D01*
G02X1464370I-4134J0D01*
G01D02*
G02X1472638I4134J0D01*
G02X1464370I-4134J0D01*
G01X1440748Y659961D02*
G02X1449016I4134J0D01*
G02X1440748I-4134J0D01*
G01D02*
G02X1449016I4134J0D01*
G02X1440748I-4134J0D01*
G01X1486693Y10197D02*
G02X1496142I4725J0D01*
G02X1486693I-4725J0D01*
G01D02*
G02X1496142I4725J0D01*
G02X1486693I-4725J0D01*
G01X1520226Y639094D02*
G02X1528593I4183J0D01*
G02X1520226I-4184J0D01*
G01D02*
G02X1528593I4183J0D01*
G02X1520226I-4184J0D01*
G01X1679134Y17717D02*
Y23763D01*
G03X1676711Y32156I-15749J0D01*
G02X1693368I8329J5246D01*
G03X1690945Y23763I13326J-8393D01*
G01Y17717D01*
G02X1679134I-5905J0D01*
G01Y23763D02*
G03X1676711Y32156I-15749J0D01*
G02X1693368I8329J5246D01*
G03X1690945Y23763I13326J-8393D01*
G01Y17717D01*
G02X1679134I-5905J0D01*
G01Y23763D01*
G01X1665354Y236614D02*
G02X1681102I7874J0D01*
G02X1665354I-7874J0D01*
G01D02*
G02X1681102I7874J0D01*
G02X1665354I-7874J0D01*
G01X1679134Y330709D02*
Y336756D01*
G03X1676711Y345148I-15747J-1D01*
G02X1693368I8329J5246D01*
G03X1690945Y336756I13324J-8393D01*
G01Y330709D01*
G02X1679134I-5905J0D01*
G01Y336756D02*
G03X1676711Y345148I-15747J-1D01*
G02X1693368I8329J5246D01*
G03X1690945Y336756I13324J-8393D01*
G01Y330709D01*
G02X1679134I-5905J0D01*
G01Y336756D01*
G01X1665354Y411614D02*
G02X1681102I7874J0D01*
G02X1665354I-7874J0D01*
G01D02*
G02X1681102I7874J0D01*
G02X1665354I-7874J0D01*
G01X1660630Y498031D02*
G02X1685827I12599J0D01*
G02X1660630I-12599J0D01*
G01D02*
G02X1685827I12599J0D01*
G02X1660630I-12599J0D01*
G01X1687402Y541339D02*
G02X1712598I12598J0D01*
G02X1687402I-12598J0D01*
G01D02*
G02X1712598I12598J0D01*
G02X1687402I-12598J0D01*
G01X1805118Y96457D02*
G02X1793307I-5906J0D01*
G01Y102504D01*
G03X1790884Y110896I-15747J-1D01*
G02X1807541I8329J5246D01*
G03X1805118Y102504I13324J-8393D01*
G01Y96457D01*
G01X1793307D02*
Y102504D01*
G03X1790884Y110896I-15747J-1D01*
G02X1807541I8329J5246D01*
G03X1805118Y102504I13324J-8393D01*
G01Y96457D01*
G02X1793307I-5906J0D01*
G01X1805118Y478346D02*
G02X1793307I-5906J0D01*
G01Y484393D01*
G03X1790884Y492786I-15749J0D01*
G02X1807541I8329J5246D01*
G03X1805118Y484393I13326J-8393D01*
G01Y478346D01*
G01X1793307D02*
Y484393D01*
G03X1790884Y492786I-15749J0D01*
G02X1807541I8329J5246D01*
G03X1805118Y484393I13326J-8393D01*
G01Y478346D01*
G02X1793307I-5906J0D01*
G01X1839865Y94037D02*
G03X1836480Y95965I-3386J-2009D01*
G01X1833031D01*
G02X1830079Y98917I0J2952D01*
G01Y99508D01*
G02X1833031Y102461I2952J1D01*
G01X1836480D01*
G03X1839865Y104388I0J3937D01*
G02Y94037I8718J-5176D01*
G01D02*
G03X1836480Y95965I-3386J-2009D01*
G01X1833031D01*
G02X1830079Y98917I0J2952D01*
G01Y99508D01*
G02X1833031Y102461I2952J1D01*
G01X1836480D01*
G03X1839865Y104388I0J3937D01*
G02Y94037I8718J-5176D01*
G01Y476518D02*
G03X1836480Y478445I-3385J-2010D01*
G01X1833031D01*
G02X1830079Y481398I0J2953D01*
G01Y481988D01*
G02X1833031Y484941I2952J0D01*
G01X1836480D01*
G03X1839865Y486868I0J3937D01*
G02Y476518I8717J-5175D01*
G01D02*
G03X1836480Y478445I-3385J-2010D01*
G01X1833031D01*
G02X1830079Y481398I0J2953D01*
G01Y481988D01*
G02X1833031Y484941I2953J0D01*
G01X1836480D01*
G03X1839865Y486868I0J3937D01*
G02Y476518I8717J-5175D01*
G01X-457143Y-1211429D02*
Y2242857D01*
X4308572D01*
Y-1211429D01*
X-457143D01*
G01X3604Y-737942D02*
X6704D01*
Y-738862D01*
X6549Y-739169D01*
X6187Y-739399D01*
X5774Y-739476D01*
X5361Y-739399D01*
X5051Y-739207D01*
X4896Y-738862D01*
Y-737942D01*
G01X3501Y-741119D02*
X6704Y-742499D01*
G01X3604Y-744027D02*
X6704D01*
X3604Y-745791D01*
X6704D01*
G01X3501Y-748009D02*
X3552Y-747932D01*
X3656D01*
X3707Y-748009D01*
X3656Y-748086D01*
X3552D01*
X3501Y-748009D01*
G01X4896D02*
X4947Y-747932D01*
X5051D01*
X5102Y-748009D01*
X5051Y-748086D01*
X4947D01*
X4896Y-748009D01*
G01X3604Y-750266D02*
X6704D01*
Y-751032D01*
X6549Y-751339D01*
X6342Y-751569D01*
X6032Y-751761D01*
X5671Y-751914D01*
X5154Y-751952D01*
X4637Y-751914D01*
X4276Y-751761D01*
X3966Y-751569D01*
X3759Y-751339D01*
X3604Y-751032D01*
Y-750266D01*
G01Y-753251D02*
X6704Y-754209D01*
X3604Y-755167D01*
G01X4689Y-754822D02*
Y-753596D01*
G01X3604Y-756581D02*
X6704D01*
Y-758037D01*
G01X5206Y-757501D02*
Y-756581D01*
G01X6704Y-760409D02*
X6601Y-760102D01*
X6342Y-759872D01*
X6032Y-759719D01*
X5619Y-759604D01*
X5154Y-759566D01*
X4689Y-759604D01*
X4276Y-759719D01*
X3966Y-759872D01*
X3707Y-760102D01*
X3604Y-760409D01*
X3707Y-760716D01*
X3966Y-760946D01*
X4276Y-761099D01*
X4689Y-761214D01*
X5154Y-761252D01*
X5619Y-761214D01*
X6032Y-761099D01*
X6342Y-760946D01*
X6601Y-760716D01*
X6704Y-760409D01*
G01Y-763509D02*
X3604D01*
G01X6704Y-762627D02*
Y-764391D01*
G01X3604Y-765842D02*
X6704D01*
Y-766762D01*
X6549Y-767069D01*
X6187Y-767299D01*
X5774Y-767376D01*
X5361Y-767299D01*
X5051Y-767107D01*
X4896Y-766762D01*
Y-765842D01*
G01X5257Y-770016D02*
X5412Y-770169D01*
X5671Y-770284D01*
X6032Y-770361D01*
X6342Y-770284D01*
X6549Y-770131D01*
X6704Y-769862D01*
Y-768827D01*
X3604D01*
Y-770092D01*
X3811Y-770361D01*
X4121Y-770514D01*
X4482Y-770591D01*
X4844Y-770514D01*
X5154Y-770284D01*
X5257Y-770016D01*
Y-768827D01*
G01X3604Y-772809D02*
X6704D01*
X6084Y-772349D01*
G01X3604D02*
Y-773269D01*
G01Y-774951D02*
X6704Y-775909D01*
X3604Y-776867D01*
G01X4689Y-776522D02*
Y-775296D01*
G01X3604Y-778281D02*
X6704D01*
Y-779737D01*
G01X5206Y-779201D02*
Y-778281D01*
G01X6704Y-782109D02*
X6601Y-781802D01*
X6342Y-781572D01*
X6032Y-781419D01*
X5619Y-781304D01*
X5154Y-781266D01*
X4689Y-781304D01*
X4276Y-781419D01*
X3966Y-781572D01*
X3707Y-781802D01*
X3604Y-782109D01*
X3707Y-782416D01*
X3966Y-782646D01*
X4276Y-782799D01*
X4689Y-782914D01*
X5154Y-782952D01*
X5619Y-782914D01*
X6032Y-782799D01*
X6342Y-782646D01*
X6601Y-782416D01*
X6704Y-782109D01*
G01X44845Y58500D02*
Y61600D01*
G01X46455D02*
Y58500D01*
G01Y60050D02*
X44845D01*
G01X48022Y61083D02*
X48252Y61393D01*
X48520Y61548D01*
X48827Y61600D01*
X49210Y61497D01*
X49478Y61238D01*
X49555Y60928D01*
X49517Y60618D01*
X49363Y60360D01*
X48597Y59843D01*
X48252Y59482D01*
X48022Y58965D01*
X47945Y58500D01*
X49555D01*
G01X90551Y236614D02*
G03I-31496J0D01*
G01Y411594D02*
G03I-31496J0D01*
G01X36595Y514450D02*
Y517550D01*
G01X38205D02*
Y514450D01*
G01Y516000D02*
X36595D01*
G01X40500Y514450D02*
Y517550D01*
X40040Y516930D01*
G01Y514450D02*
X40960D01*
G01X42948Y514812D02*
X43217Y514553D01*
X43523Y514450D01*
X43830Y514553D01*
X44098Y514863D01*
X44290Y515328D01*
X44367Y515793D01*
Y516362D01*
X44290Y516827D01*
X44098Y517240D01*
X43868Y517447D01*
X43600Y517550D01*
X43293Y517447D01*
X43063Y517240D01*
X42910Y516930D01*
X42833Y516517D01*
X42910Y516155D01*
X43102Y515793D01*
X43332Y515587D01*
X43600Y515535D01*
X43907Y515638D01*
X44137Y515897D01*
X44367Y516362D01*
G01X71650Y-1024800D02*
X69130Y-1024383D01*
X66925Y-1022717D01*
X65035Y-1020217D01*
X63775Y-1017300D01*
X63145Y-1013967D01*
Y-1010633D01*
X63775Y-1007300D01*
X65035Y-1004383D01*
X66925Y-1001884D01*
X69130Y-1000217D01*
X71650Y-999800D01*
X74170Y-1000217D01*
X76375Y-1001884D01*
X78265Y-1004383D01*
X79525Y-1007300D01*
X80155Y-1010633D01*
Y-1013967D01*
X79525Y-1017300D01*
X78265Y-1020217D01*
X76375Y-1022717D01*
X74170Y-1024383D01*
X71650Y-1024800D01*
G01X74170Y-1018133D02*
X77950Y-1024800D01*
G01X91495Y-1008134D02*
Y-1019800D01*
X92755Y-1022717D01*
X94645Y-1024383D01*
X96850Y-1024800D01*
X99055Y-1024383D01*
X100945Y-1022717D01*
X102205Y-1019800D01*
G01Y-1024800D02*
Y-1008134D01*
G01X127720Y-1024800D02*
Y-1008134D01*
G01Y-1011050D02*
X126460Y-1009384D01*
X124570Y-1008550D01*
X122365Y-1008134D01*
X120160Y-1008967D01*
X118270Y-1010633D01*
X117010Y-1013134D01*
X116380Y-1016467D01*
X117010Y-1019800D01*
X118270Y-1022301D01*
X120160Y-1023967D01*
X122365Y-1024800D01*
X124570Y-1024383D01*
X126460Y-1023134D01*
X127720Y-1021467D01*
G01X141895Y-1024800D02*
Y-1008134D01*
G01Y-1012300D02*
X143155Y-1010217D01*
X145045Y-1008550D01*
X147565Y-1008134D01*
X149770Y-1008550D01*
X151660Y-1010217D01*
X152605Y-1013134D01*
Y-1024800D01*
G01X172450Y-999800D02*
Y-1024800D01*
G01X168040Y-1008134D02*
X176860D01*
G01X203320Y-1024800D02*
Y-1008134D01*
G01Y-1011050D02*
X202060Y-1009384D01*
X200170Y-1008550D01*
X197965Y-1008134D01*
X195760Y-1008967D01*
X193870Y-1010633D01*
X192610Y-1013134D01*
X191980Y-1016467D01*
X192610Y-1019800D01*
X193870Y-1022301D01*
X195760Y-1023967D01*
X197965Y-1024800D01*
X200170Y-1024383D01*
X202060Y-1023134D01*
X203320Y-1021467D01*
G01X49820Y-1042350D02*
X51387D01*
Y-1044240D01*
X50917Y-1044870D01*
X50368Y-1045290D01*
X49585Y-1045500D01*
X48802Y-1045290D01*
X48253Y-1044870D01*
X47783Y-1044240D01*
X47470Y-1043505D01*
X47313Y-1042665D01*
Y-1041930D01*
X47470Y-1041300D01*
X47783Y-1040565D01*
X48253Y-1039935D01*
X48723Y-1039515D01*
X49350Y-1039200D01*
X49898D01*
X50525Y-1039410D01*
X50995Y-1039830D01*
G01X53927Y-1039200D02*
Y-1043715D01*
X54240Y-1044660D01*
X54867Y-1045290D01*
X55650Y-1045500D01*
X56433Y-1045290D01*
X57060Y-1044660D01*
X57373Y-1043715D01*
Y-1039200D01*
G01X61010D02*
X62890D01*
G01X61950D02*
Y-1045500D01*
G01X61010D02*
X62890D01*
G01X66605Y-1044660D02*
X67232Y-1045185D01*
X67937Y-1045500D01*
X68563D01*
X69190Y-1045185D01*
X69660Y-1044660D01*
X69895Y-1043925D01*
X69738Y-1043190D01*
X69347Y-1042560D01*
X68642Y-1042140D01*
X67702Y-1041930D01*
X67153Y-1041510D01*
X66918Y-1040775D01*
X67075Y-1040040D01*
X67467Y-1039515D01*
X68015Y-1039200D01*
X68563D01*
X69112Y-1039410D01*
X69582Y-1039935D01*
G01X72905Y-1045500D02*
Y-1039200D01*
G01X76195D02*
Y-1045500D01*
G01Y-1042350D02*
X72905D01*
G01X78892Y-1045500D02*
X80850Y-1039200D01*
X82808Y-1045500D01*
G01X82103Y-1043295D02*
X79597D01*
G01X85348Y-1045500D02*
Y-1039200D01*
X88952Y-1045500D01*
Y-1039200D01*
G01X98027Y-1045500D02*
Y-1039200D01*
X99593D01*
X100220Y-1039515D01*
X100690Y-1039935D01*
X101082Y-1040565D01*
X101395Y-1041300D01*
X101473Y-1042350D01*
X101395Y-1043400D01*
X101082Y-1044135D01*
X100690Y-1044765D01*
X100220Y-1045185D01*
X99593Y-1045500D01*
X98027D01*
G01X105110Y-1039200D02*
X106990D01*
G01X106050D02*
Y-1045500D01*
G01X105110D02*
X106990D01*
G01X110705Y-1044660D02*
X111332Y-1045185D01*
X112037Y-1045500D01*
X112663D01*
X113290Y-1045185D01*
X113760Y-1044660D01*
X113995Y-1043925D01*
X113838Y-1043190D01*
X113447Y-1042560D01*
X112742Y-1042140D01*
X111802Y-1041930D01*
X111253Y-1041510D01*
X111018Y-1040775D01*
X111175Y-1040040D01*
X111567Y-1039515D01*
X112115Y-1039200D01*
X112663D01*
X113212Y-1039410D01*
X113682Y-1039935D01*
G01X118650Y-1039200D02*
Y-1045500D01*
G01X116848Y-1039200D02*
X120452D01*
G01X124950Y-1045710D02*
X124793Y-1045605D01*
Y-1045395D01*
X124950Y-1045290D01*
X125107Y-1045395D01*
Y-1045605D01*
X124950Y-1045710D01*
G01X131093Y-1046655D02*
X131407Y-1045290D01*
G01X137550Y-1039200D02*
Y-1045500D01*
G01X135748Y-1039200D02*
X139352D01*
G01X141892Y-1045500D02*
X143850Y-1039200D01*
X145808Y-1045500D01*
G01X145103Y-1043295D02*
X142597D01*
G01X150150Y-1045500D02*
X149523Y-1045395D01*
X148975Y-1044975D01*
X148505Y-1044345D01*
X148192Y-1043610D01*
X148035Y-1042770D01*
Y-1041930D01*
X148192Y-1041090D01*
X148505Y-1040355D01*
X148975Y-1039725D01*
X149523Y-1039305D01*
X150150Y-1039200D01*
X150777Y-1039305D01*
X151325Y-1039725D01*
X151795Y-1040355D01*
X152108Y-1041090D01*
X152265Y-1041930D01*
Y-1042770D01*
X152108Y-1043610D01*
X151795Y-1044345D01*
X151325Y-1044975D01*
X150777Y-1045395D01*
X150150Y-1045500D01*
G01X156450D02*
Y-1042665D01*
X154883Y-1039200D01*
G01X158017D02*
X156450Y-1042665D01*
G01X161027Y-1039200D02*
Y-1043715D01*
X161340Y-1044660D01*
X161967Y-1045290D01*
X162750Y-1045500D01*
X163533Y-1045290D01*
X164160Y-1044660D01*
X164473Y-1043715D01*
Y-1039200D01*
G01X167092Y-1045500D02*
X169050Y-1039200D01*
X171008Y-1045500D01*
G01X170303Y-1043295D02*
X167797D01*
G01X173548Y-1045500D02*
Y-1039200D01*
X177152Y-1045500D01*
Y-1039200D01*
G01X51073Y-1049725D02*
X50603Y-1049410D01*
X50055Y-1049200D01*
X49428D01*
X48723Y-1049515D01*
X48175Y-1050040D01*
X47783Y-1050670D01*
X47470Y-1051720D01*
X47392Y-1052665D01*
X47548Y-1053610D01*
X47783Y-1054240D01*
X48253Y-1054870D01*
X48802Y-1055290D01*
X49350Y-1055500D01*
X49898D01*
X50447Y-1055290D01*
X50917Y-1054975D01*
X51308Y-1054555D01*
G01X54710Y-1049200D02*
X56590D01*
G01X55650D02*
Y-1055500D01*
G01X54710D02*
X56590D01*
G01X61950Y-1049200D02*
Y-1055500D01*
G01X60148Y-1049200D02*
X63752D01*
G01X68250Y-1055500D02*
Y-1052665D01*
X66683Y-1049200D01*
G01X69817D02*
X68250Y-1052665D01*
G01X79127Y-1054240D02*
X79597Y-1054975D01*
X80223Y-1055395D01*
X80928Y-1055500D01*
X81555Y-1055395D01*
X82182Y-1054870D01*
X82573Y-1054240D01*
X82652Y-1053610D01*
X82495Y-1052875D01*
X81947Y-1052350D01*
X81398Y-1052140D01*
X80693D01*
G01X81398D02*
X81868Y-1051825D01*
X82260Y-1051300D01*
X82417Y-1050670D01*
X82260Y-1050040D01*
X81868Y-1049515D01*
X81163Y-1049200D01*
X80458Y-1049305D01*
X79753Y-1049725D01*
G01X85427Y-1054240D02*
X85897Y-1054975D01*
X86523Y-1055395D01*
X87228Y-1055500D01*
X87855Y-1055395D01*
X88482Y-1054870D01*
X88873Y-1054240D01*
X88952Y-1053610D01*
X88795Y-1052875D01*
X88247Y-1052350D01*
X87698Y-1052140D01*
X86993D01*
G01X87698D02*
X88168Y-1051825D01*
X88560Y-1051300D01*
X88717Y-1050670D01*
X88560Y-1050040D01*
X88168Y-1049515D01*
X87463Y-1049200D01*
X86758Y-1049305D01*
X86053Y-1049725D01*
G01X91727Y-1054240D02*
X92197Y-1054975D01*
X92823Y-1055395D01*
X93528Y-1055500D01*
X94155Y-1055395D01*
X94782Y-1054870D01*
X95173Y-1054240D01*
X95252Y-1053610D01*
X95095Y-1052875D01*
X94547Y-1052350D01*
X93998Y-1052140D01*
X93293D01*
G01X93998D02*
X94468Y-1051825D01*
X94860Y-1051300D01*
X95017Y-1050670D01*
X94860Y-1050040D01*
X94468Y-1049515D01*
X93763Y-1049200D01*
X93058Y-1049305D01*
X92353Y-1049725D01*
G01X99593Y-1055500D02*
X99750Y-1054135D01*
X99985Y-1052980D01*
X100298Y-1051930D01*
X100690Y-1050775D01*
X101317Y-1049200D01*
X98183D01*
G01X105893Y-1055500D02*
X106050Y-1054135D01*
X106285Y-1052980D01*
X106598Y-1051930D01*
X106990Y-1050775D01*
X107617Y-1049200D01*
X104483D01*
G01X112193Y-1056655D02*
X112507Y-1055290D01*
G01X118650Y-1049200D02*
Y-1055500D01*
G01X116848Y-1049200D02*
X120452D01*
G01X122992Y-1055500D02*
X124950Y-1049200D01*
X126908Y-1055500D01*
G01X126203Y-1053295D02*
X123697D01*
G01X130310Y-1049200D02*
X132190D01*
G01X131250D02*
Y-1055500D01*
G01X130310D02*
X132190D01*
G01X135200Y-1049200D02*
X136297Y-1055500D01*
X137550Y-1049200D01*
X138803Y-1055500D01*
X139900Y-1049200D01*
G01X141892Y-1055500D02*
X143850Y-1049200D01*
X145808Y-1055500D01*
G01X145103Y-1053295D02*
X142597D01*
G01X148348Y-1055500D02*
Y-1049200D01*
X151952Y-1055500D01*
Y-1049200D01*
G01X162358Y-1057600D02*
X161575Y-1056550D01*
X161183Y-1055500D01*
Y-1051300D01*
X161575Y-1050250D01*
X162358Y-1049200D01*
G01X173783Y-1055500D02*
Y-1049200D01*
X175742D01*
X176368Y-1049515D01*
X176760Y-1049935D01*
X176917Y-1050775D01*
X176760Y-1051615D01*
X176290Y-1052140D01*
X175742Y-1052455D01*
X173783D01*
G01X175742D02*
X176917Y-1055500D01*
G01X181650Y-1055710D02*
X181493Y-1055605D01*
Y-1055395D01*
X181650Y-1055290D01*
X181807Y-1055395D01*
Y-1055605D01*
X181650Y-1055710D01*
G01X187950Y-1055500D02*
X187323Y-1055395D01*
X186775Y-1054975D01*
X186305Y-1054345D01*
X185992Y-1053610D01*
X185835Y-1052770D01*
Y-1051930D01*
X185992Y-1051090D01*
X186305Y-1050355D01*
X186775Y-1049725D01*
X187323Y-1049305D01*
X187950Y-1049200D01*
X188577Y-1049305D01*
X189125Y-1049725D01*
X189595Y-1050355D01*
X189908Y-1051090D01*
X190065Y-1051930D01*
Y-1052770D01*
X189908Y-1053610D01*
X189595Y-1054345D01*
X189125Y-1054975D01*
X188577Y-1055395D01*
X187950Y-1055500D01*
G01X194250Y-1055710D02*
X194093Y-1055605D01*
Y-1055395D01*
X194250Y-1055290D01*
X194407Y-1055395D01*
Y-1055605D01*
X194250Y-1055710D01*
G01X202273Y-1049725D02*
X201803Y-1049410D01*
X201255Y-1049200D01*
X200628D01*
X199923Y-1049515D01*
X199375Y-1050040D01*
X198983Y-1050670D01*
X198670Y-1051720D01*
X198592Y-1052665D01*
X198748Y-1053610D01*
X198983Y-1054240D01*
X199453Y-1054870D01*
X200002Y-1055290D01*
X200550Y-1055500D01*
X201098D01*
X201647Y-1055290D01*
X202117Y-1054975D01*
X202508Y-1054555D01*
G01X206850Y-1055710D02*
X206693Y-1055605D01*
Y-1055395D01*
X206850Y-1055290D01*
X207007Y-1055395D01*
Y-1055605D01*
X206850Y-1055710D01*
G01X213542Y-1057600D02*
X214325Y-1056550D01*
X214717Y-1055500D01*
Y-1051300D01*
X214325Y-1050250D01*
X213542Y-1049200D01*
G01X47548Y-1035500D02*
Y-1029200D01*
X51152Y-1035500D01*
Y-1029200D01*
G01X55650Y-1035500D02*
X55023Y-1035395D01*
X54475Y-1034975D01*
X54005Y-1034345D01*
X53692Y-1033610D01*
X53535Y-1032770D01*
Y-1031930D01*
X53692Y-1031090D01*
X54005Y-1030355D01*
X54475Y-1029725D01*
X55023Y-1029305D01*
X55650Y-1029200D01*
X56277Y-1029305D01*
X56825Y-1029725D01*
X57295Y-1030355D01*
X57608Y-1031090D01*
X57765Y-1031930D01*
Y-1032770D01*
X57608Y-1033610D01*
X57295Y-1034345D01*
X56825Y-1034975D01*
X56277Y-1035395D01*
X55650Y-1035500D01*
G01X61950Y-1035710D02*
X61793Y-1035605D01*
Y-1035395D01*
X61950Y-1035290D01*
X62107Y-1035395D01*
Y-1035605D01*
X61950Y-1035710D01*
G01X66762Y-1030250D02*
X67232Y-1029620D01*
X67780Y-1029305D01*
X68407Y-1029200D01*
X69190Y-1029410D01*
X69738Y-1029935D01*
X69895Y-1030565D01*
X69817Y-1031195D01*
X69503Y-1031720D01*
X67937Y-1032770D01*
X67232Y-1033505D01*
X66762Y-1034555D01*
X66605Y-1035500D01*
X69895D01*
G01X74550D02*
Y-1029200D01*
X73610Y-1030460D01*
G01Y-1035500D02*
X75490D01*
G01X80850D02*
Y-1029200D01*
X79910Y-1030460D01*
G01Y-1035500D02*
X81790D01*
G01X86993Y-1036655D02*
X87307Y-1035290D01*
G01X91100Y-1029200D02*
X92197Y-1035500D01*
X93450Y-1029200D01*
X94703Y-1035500D01*
X95800Y-1029200D01*
G01X101317Y-1035500D02*
X98183D01*
Y-1029200D01*
X101317D01*
G01X100063Y-1032245D02*
X98183D01*
G01X104248Y-1035500D02*
Y-1029200D01*
X107852Y-1035500D01*
Y-1029200D01*
G01X110705Y-1035500D02*
Y-1029200D01*
G01X113995D02*
Y-1035500D01*
G01Y-1032350D02*
X110705D01*
G01X116927Y-1029200D02*
Y-1033715D01*
X117240Y-1034660D01*
X117867Y-1035290D01*
X118650Y-1035500D01*
X119433Y-1035290D01*
X120060Y-1034660D01*
X120373Y-1033715D01*
Y-1029200D01*
G01X122992Y-1035500D02*
X124950Y-1029200D01*
X126908Y-1035500D01*
G01X126203Y-1033295D02*
X123697D01*
G01X136062Y-1030250D02*
X136532Y-1029620D01*
X137080Y-1029305D01*
X137707Y-1029200D01*
X138490Y-1029410D01*
X139038Y-1029935D01*
X139195Y-1030565D01*
X139117Y-1031195D01*
X138803Y-1031720D01*
X137237Y-1032770D01*
X136532Y-1033505D01*
X136062Y-1034555D01*
X135905Y-1035500D01*
X139195D01*
G01X142048D02*
Y-1029200D01*
X145652Y-1035500D01*
Y-1029200D01*
G01X148427Y-1035500D02*
Y-1029200D01*
X149993D01*
X150620Y-1029515D01*
X151090Y-1029935D01*
X151482Y-1030565D01*
X151795Y-1031300D01*
X151873Y-1032350D01*
X151795Y-1033400D01*
X151482Y-1034135D01*
X151090Y-1034765D01*
X150620Y-1035185D01*
X149993Y-1035500D01*
X148427D01*
G01X161183D02*
Y-1029200D01*
X163142D01*
X163768Y-1029515D01*
X164160Y-1029935D01*
X164317Y-1030775D01*
X164160Y-1031615D01*
X163690Y-1032140D01*
X163142Y-1032455D01*
X161183D01*
G01X163142D02*
X164317Y-1035500D01*
G01X167327D02*
Y-1029200D01*
X168893D01*
X169520Y-1029515D01*
X169990Y-1029935D01*
X170382Y-1030565D01*
X170695Y-1031300D01*
X170773Y-1032350D01*
X170695Y-1033400D01*
X170382Y-1034135D01*
X169990Y-1034765D01*
X169520Y-1035185D01*
X168893Y-1035500D01*
X167327D01*
G01X175350Y-1035710D02*
X175193Y-1035605D01*
Y-1035395D01*
X175350Y-1035290D01*
X175507Y-1035395D01*
Y-1035605D01*
X175350Y-1035710D01*
G01X55345Y270500D02*
Y273600D01*
G01X56955D02*
Y270500D01*
G01Y272050D02*
X55345D01*
G01X58522Y273083D02*
X58752Y273393D01*
X59020Y273548D01*
X59327Y273600D01*
X59710Y273497D01*
X59978Y273238D01*
X60055Y272928D01*
X60017Y272618D01*
X59863Y272360D01*
X59097Y271843D01*
X58752Y271482D01*
X58522Y270965D01*
X58445Y270500D01*
X60055D01*
G01X61622Y273083D02*
X61852Y273393D01*
X62120Y273548D01*
X62427Y273600D01*
X62810Y273497D01*
X63078Y273238D01*
X63155Y272928D01*
X63117Y272618D01*
X62963Y272360D01*
X62197Y271843D01*
X61852Y271482D01*
X61622Y270965D01*
X61545Y270500D01*
X63155D01*
G01X45345Y308000D02*
Y311100D01*
G01X46955D02*
Y308000D01*
G01Y309550D02*
X45345D01*
G01X49250Y308000D02*
Y311100D01*
X48790Y310480D01*
G01Y308000D02*
X49710D01*
G01X55345Y445000D02*
Y448100D01*
G01X56955D02*
Y445000D01*
G01Y446550D02*
X55345D01*
G01X58522Y447583D02*
X58752Y447893D01*
X59020Y448048D01*
X59327Y448100D01*
X59710Y447997D01*
X59978Y447738D01*
X60055Y447428D01*
X60017Y447118D01*
X59863Y446860D01*
X59097Y446343D01*
X58752Y445982D01*
X58522Y445465D01*
X58445Y445000D01*
X60055D01*
G01X62350D02*
Y448100D01*
X61890Y447480D01*
G01Y445000D02*
X62810D01*
G01X69595Y473950D02*
Y477050D01*
G01X71205D02*
Y473950D01*
G01Y475500D02*
X69595D01*
G01X72657Y474570D02*
X72887Y474208D01*
X73193Y474002D01*
X73538Y473950D01*
X73845Y474002D01*
X74152Y474260D01*
X74343Y474570D01*
X74382Y474880D01*
X74305Y475242D01*
X74037Y475500D01*
X73768Y475603D01*
X73423D01*
G01X73768D02*
X73998Y475758D01*
X74190Y476017D01*
X74267Y476327D01*
X74190Y476637D01*
X73998Y476895D01*
X73653Y477050D01*
X73308Y476998D01*
X72963Y476792D01*
G01X75872Y475242D02*
X76140Y475603D01*
X76370Y475810D01*
X76677Y475913D01*
X76945Y475810D01*
X77137Y475603D01*
X77290Y475293D01*
X77328Y474932D01*
X77290Y474622D01*
X77137Y474312D01*
X76907Y474053D01*
X76638Y473950D01*
X76332Y474053D01*
X76063Y474363D01*
X75910Y474828D01*
X75872Y475345D01*
X75948Y476017D01*
X76063Y476378D01*
X76255Y476740D01*
X76523Y476998D01*
X76792Y477050D01*
X77060Y476947D01*
X77252Y476688D01*
G01X107233Y107500D02*
Y112500D01*
X108753D01*
X109260Y112250D01*
X109640Y111667D01*
X109767Y111000D01*
X109640Y110333D01*
X109323Y109833D01*
X108753Y109583D01*
X107233D01*
G01X112207Y108250D02*
X112587Y107833D01*
X113030Y107583D01*
X113600Y107500D01*
X114170Y107667D01*
X114613Y108000D01*
X114930Y108583D01*
X114993Y109250D01*
X114867Y109917D01*
X114550Y110333D01*
X114107Y110667D01*
X113663Y110750D01*
X113220Y110667D01*
X112650Y110333D01*
X112840Y112500D01*
X114550D01*
G01X117497Y111667D02*
X117877Y112167D01*
X118320Y112417D01*
X118827Y112500D01*
X119460Y112333D01*
X119903Y111917D01*
X120030Y111417D01*
X119967Y110917D01*
X119713Y110500D01*
X118447Y109667D01*
X117877Y109083D01*
X117497Y108250D01*
X117370Y107500D01*
X120030D01*
G01X122217Y112500D02*
X123800Y107500D01*
X125383Y112500D01*
G01X127000Y105833D02*
X130800D01*
G01X132670Y107500D02*
Y112500D01*
G01X135330D02*
Y107500D01*
G01Y110000D02*
X132670D01*
G01X137770Y108167D02*
X138277Y107750D01*
X138847Y107500D01*
X139353D01*
X139860Y107750D01*
X140240Y108167D01*
X140430Y108750D01*
X140303Y109333D01*
X139987Y109833D01*
X139417Y110167D01*
X138657Y110333D01*
X138213Y110667D01*
X138023Y111250D01*
X138150Y111833D01*
X138467Y112250D01*
X138910Y112500D01*
X139353D01*
X139797Y112333D01*
X140177Y111917D01*
G01X142997Y111667D02*
X143377Y112167D01*
X143820Y112417D01*
X144327Y112500D01*
X144960Y112333D01*
X145403Y111917D01*
X145530Y111417D01*
X145467Y110917D01*
X145213Y110500D01*
X143947Y109667D01*
X143377Y109083D01*
X142997Y108250D01*
X142870Y107500D01*
X145530D01*
G01X129407Y114000D02*
Y117100D01*
X130173D01*
X130480Y116945D01*
X130710Y116738D01*
X130902Y116428D01*
X131055Y116067D01*
X131093Y115550D01*
X131055Y115033D01*
X130902Y114672D01*
X130710Y114362D01*
X130480Y114155D01*
X130173Y114000D01*
X129407D01*
G01X132622Y116583D02*
X132852Y116893D01*
X133120Y117048D01*
X133427Y117100D01*
X133810Y116997D01*
X134078Y116738D01*
X134155Y116428D01*
X134117Y116118D01*
X133963Y115860D01*
X133197Y115343D01*
X132852Y114982D01*
X132622Y114465D01*
X132545Y114000D01*
X134155D01*
G01X142084Y141850D02*
X124486D01*
Y149150D01*
X142084D01*
Y141850D01*
G01X124486Y140150D02*
X142084D01*
Y132850D01*
X124486D01*
Y140150D01*
G01X142084Y123850D02*
X124486D01*
Y131150D01*
X142084D01*
Y123850D01*
G01X130265Y122400D02*
X137355D01*
Y118600D01*
X130265D01*
G01X129665Y122400D02*
X136855D01*
Y118600D01*
X129665D01*
G01X129265Y122400D02*
X136355D01*
Y118600D01*
X129215D01*
Y122350D01*
G01X142084Y159850D02*
X124486D01*
Y167150D01*
X142084D01*
Y159850D01*
G01X124486Y158150D02*
X142084D01*
Y150850D01*
X124486D01*
Y158150D01*
G01X203202Y215236D02*
G03I-36417J0D01*
G01X166785D02*
X130353D01*
X203202D01*
G01Y295236D02*
G03I-36417J0D01*
G01X166785D02*
X130353D01*
X203202D01*
G01Y375236D02*
G03I-36417J0D01*
G01X166785D02*
X130353D01*
X203202D01*
G01Y455236D02*
G03I-36417J0D01*
G01X166785D02*
X130353D01*
X203202D01*
G01Y535236D02*
G03I-36417J0D01*
G01X166785D02*
X130353D01*
X203202D01*
G01X119036Y582785D02*
Y590285D01*
X121276D01*
X122023Y589910D01*
X122583Y589035D01*
X122770Y588035D01*
X122583Y587035D01*
X122116Y586285D01*
X121276Y585910D01*
X119036D01*
G01X126536Y582785D02*
Y590285D01*
X128870D01*
X129616Y589910D01*
X130083Y589410D01*
X130270Y588410D01*
X130083Y587410D01*
X129523Y586785D01*
X128870Y586410D01*
X126536D01*
G01X128870D02*
X130270Y582785D01*
G01X137770D02*
X134036D01*
Y590285D01*
X137770D01*
G01X136276Y586660D02*
X134036D01*
G01X141443Y583785D02*
X142190Y583160D01*
X143030Y582785D01*
X143776D01*
X144523Y583160D01*
X145083Y583785D01*
X145363Y584660D01*
X145176Y585535D01*
X144710Y586285D01*
X143870Y586785D01*
X142750Y587035D01*
X142096Y587535D01*
X141816Y588410D01*
X142003Y589285D01*
X142470Y589910D01*
X143123Y590285D01*
X143776D01*
X144430Y590035D01*
X144990Y589410D01*
G01X148943Y583785D02*
X149690Y583160D01*
X150530Y582785D01*
X151276D01*
X152023Y583160D01*
X152583Y583785D01*
X152863Y584660D01*
X152676Y585535D01*
X152210Y586285D01*
X151370Y586785D01*
X150250Y587035D01*
X149596Y587535D01*
X149316Y588410D01*
X149503Y589285D01*
X149970Y589910D01*
X150623Y590285D01*
X151276D01*
X151930Y590035D01*
X152490Y589410D01*
G01X157190Y585285D02*
X159616D01*
G01X164130Y582785D02*
Y590285D01*
X167676D01*
G01X166370Y586660D02*
X164130D01*
G01X172283Y590285D02*
X174523D01*
G01X173403D02*
Y582785D01*
G01X172283D02*
X174523D01*
G01X180903Y590285D02*
Y582785D01*
G01X178756Y590285D02*
X183050D01*
G01X124016Y726496D02*
X177165D01*
Y593819D01*
X124016D01*
Y726496D01*
G01X112205Y738307D02*
X188976D01*
Y582008D01*
X112205D01*
Y738307D01*
G01X124016Y690276D02*
X177165D01*
G01X155483Y74000D02*
Y77100D01*
X156403D01*
X156710Y76945D01*
X156940Y76583D01*
X157017Y76170D01*
X156940Y75757D01*
X156748Y75447D01*
X156403Y75292D01*
X155483D01*
G01X158583Y74000D02*
Y77100D01*
X159542D01*
X159848Y76945D01*
X160040Y76738D01*
X160117Y76325D01*
X160040Y75912D01*
X159810Y75653D01*
X159542Y75498D01*
X158583D01*
G01X159542D02*
X160117Y74000D01*
G01X162450D02*
Y77100D01*
X161990Y76480D01*
G01Y74000D02*
X162910D01*
G01X165550Y77100D02*
X165243Y76997D01*
X165013Y76738D01*
X164860Y76428D01*
X164745Y76015D01*
X164707Y75550D01*
X164745Y75085D01*
X164860Y74672D01*
X165013Y74362D01*
X165243Y74103D01*
X165550Y74000D01*
X165857Y74103D01*
X166087Y74362D01*
X166240Y74672D01*
X166355Y75085D01*
X166393Y75550D01*
X166355Y76015D01*
X166240Y76428D01*
X166087Y76738D01*
X165857Y76997D01*
X165550Y77100D01*
G01X168573Y74000D02*
X168650Y74672D01*
X168765Y75240D01*
X168918Y75757D01*
X169110Y76325D01*
X169417Y77100D01*
X167883D01*
G01X159885Y107889D02*
X173685D01*
G01X147100Y158148D02*
Y107889D01*
X153685D01*
G01X155983Y88500D02*
Y91600D01*
X156903D01*
X157210Y91445D01*
X157440Y91083D01*
X157517Y90670D01*
X157440Y90257D01*
X157248Y89947D01*
X156903Y89792D01*
X155983D01*
G01X159083Y88500D02*
Y91600D01*
X160042D01*
X160348Y91445D01*
X160540Y91238D01*
X160617Y90825D01*
X160540Y90412D01*
X160310Y90153D01*
X160042Y89998D01*
X159083D01*
G01X160042D02*
X160617Y88500D01*
G01X162950D02*
Y91600D01*
X162490Y90980D01*
G01Y88500D02*
X163410D01*
G01X166050Y91600D02*
X165743Y91497D01*
X165513Y91238D01*
X165360Y90928D01*
X165245Y90515D01*
X165207Y90050D01*
X165245Y89585D01*
X165360Y89172D01*
X165513Y88862D01*
X165743Y88603D01*
X166050Y88500D01*
X166357Y88603D01*
X166587Y88862D01*
X166740Y89172D01*
X166855Y89585D01*
X166893Y90050D01*
X166855Y90515D01*
X166740Y90928D01*
X166587Y91238D01*
X166357Y91497D01*
X166050Y91600D01*
G01X168422Y89792D02*
X168690Y90153D01*
X168920Y90360D01*
X169227Y90463D01*
X169495Y90360D01*
X169687Y90153D01*
X169840Y89843D01*
X169878Y89482D01*
X169840Y89172D01*
X169687Y88862D01*
X169457Y88603D01*
X169188Y88500D01*
X168882Y88603D01*
X168613Y88913D01*
X168460Y89378D01*
X168422Y89895D01*
X168498Y90567D01*
X168613Y90928D01*
X168805Y91290D01*
X169073Y91548D01*
X169342Y91600D01*
X169610Y91497D01*
X169802Y91238D01*
G01X186470Y168125D02*
X147100D01*
Y168048D01*
G01X147633Y577620D02*
X147825Y577310D01*
X148055Y577103D01*
X148323Y577000D01*
X148630Y577103D01*
X148860Y577310D01*
X149090Y577620D01*
X149167Y578033D01*
Y580100D01*
G01X150733Y577000D02*
Y580100D01*
X151653D01*
X151960Y579945D01*
X152190Y579583D01*
X152267Y579170D01*
X152190Y578757D01*
X151998Y578447D01*
X151653Y578292D01*
X150733D01*
G01X153872Y579583D02*
X154102Y579893D01*
X154370Y580048D01*
X154677Y580100D01*
X155060Y579997D01*
X155328Y579738D01*
X155405Y579428D01*
X155367Y579118D01*
X155213Y578860D01*
X154447Y578343D01*
X154102Y577982D01*
X153872Y577465D01*
X153795Y577000D01*
X155405D01*
G01X178297Y16000D02*
Y21000D01*
X180703D01*
G01X179817Y18583D02*
X178297D01*
G01X183017Y16000D02*
X184600Y21000D01*
X186183Y16000D01*
G01X185613Y17750D02*
X183587D01*
G01X188243Y16000D02*
Y21000D01*
X191157Y16000D01*
Y21000D01*
G01X192900Y14333D02*
X196700D01*
G01X200407Y18667D02*
X200660Y18917D01*
X200850Y19333D01*
X200977Y19917D01*
X200850Y20417D01*
X200597Y20750D01*
X200153Y21000D01*
X198443D01*
Y16000D01*
X200533D01*
X200977Y16333D01*
X201230Y16833D01*
X201357Y17417D01*
X201230Y18000D01*
X200850Y18500D01*
X200407Y18667D01*
X198443D01*
G01X203733Y16000D02*
Y21000D01*
X205253D01*
X205760Y20750D01*
X206140Y20167D01*
X206267Y19500D01*
X206140Y18833D01*
X205823Y18333D01*
X205253Y18083D01*
X203733D01*
G01X208200Y14333D02*
X212000D01*
G01X213997Y20167D02*
X214377Y20667D01*
X214820Y20917D01*
X215327Y21000D01*
X215960Y20833D01*
X216403Y20417D01*
X216530Y19917D01*
X216467Y19417D01*
X216213Y19000D01*
X214947Y18167D01*
X214377Y17583D01*
X213997Y16750D01*
X213870Y16000D01*
X216530D01*
G01X201341Y80400D02*
X172781D01*
Y65600D01*
X201341D01*
Y80400D01*
G01Y98400D02*
X172781D01*
Y83600D01*
X201341D01*
Y98400D01*
G01X188785Y112500D02*
Y125500D01*
X203785D01*
Y112500D01*
X188785D01*
G01X179885Y107889D02*
X186470D01*
Y158148D01*
G01X180383Y99500D02*
Y102600D01*
X181303D01*
X181610Y102445D01*
X181840Y102083D01*
X181917Y101670D01*
X181840Y101257D01*
X181648Y100947D01*
X181303Y100792D01*
X180383D01*
G01X183407Y102600D02*
Y100378D01*
X183560Y99913D01*
X183867Y99603D01*
X184250Y99500D01*
X184633Y99603D01*
X184940Y99913D01*
X185093Y100378D01*
Y102600D01*
G01X187810Y99500D02*
Y102600D01*
X186392Y100378D01*
X188308D01*
G01X199357Y102169D02*
Y110831D01*
X188843D01*
Y102169D01*
X199357D01*
G01X196250Y145299D02*
Y127701D01*
X188950D01*
Y145299D01*
X196250D01*
G01X194600Y148383D02*
X191500D01*
Y149303D01*
X191655Y149610D01*
X192017Y149840D01*
X192430Y149917D01*
X192843Y149840D01*
X193153Y149648D01*
X193308Y149303D01*
Y148383D01*
G01X194600Y152250D02*
X194548Y151943D01*
X194342Y151675D01*
X194032Y151445D01*
X193670Y151292D01*
X193257Y151215D01*
X192843D01*
X192430Y151292D01*
X192068Y151445D01*
X191758Y151675D01*
X191552Y151943D01*
X191500Y152250D01*
X191552Y152557D01*
X191758Y152825D01*
X192068Y153055D01*
X192430Y153208D01*
X192843Y153285D01*
X193257D01*
X193670Y153208D01*
X194032Y153055D01*
X194342Y152825D01*
X194548Y152557D01*
X194600Y152250D01*
G01X193773Y152557D02*
X194600Y153017D01*
G01Y155350D02*
X191500D01*
X192120Y154890D01*
G01X194600D02*
Y155810D01*
G01X193308Y157722D02*
X192947Y157990D01*
X192740Y158220D01*
X192637Y158527D01*
X192740Y158795D01*
X192947Y158987D01*
X193257Y159140D01*
X193618Y159178D01*
X193928Y159140D01*
X194238Y158987D01*
X194497Y158757D01*
X194600Y158488D01*
X194497Y158182D01*
X194187Y157913D01*
X193722Y157760D01*
X193205Y157722D01*
X192533Y157798D01*
X192172Y157913D01*
X191810Y158105D01*
X191552Y158373D01*
X191500Y158642D01*
X191603Y158910D01*
X191862Y159102D01*
G01X186470Y168048D02*
Y168125D01*
G01X189483Y248500D02*
Y251600D01*
X190403D01*
X190710Y251445D01*
X190940Y251083D01*
X191017Y250670D01*
X190940Y250257D01*
X190748Y249947D01*
X190403Y249792D01*
X189483D01*
G01X194193Y251342D02*
X193963Y251497D01*
X193695Y251600D01*
X193388D01*
X193043Y251445D01*
X192775Y251187D01*
X192583Y250877D01*
X192430Y250360D01*
X192392Y249895D01*
X192468Y249430D01*
X192583Y249120D01*
X192813Y248810D01*
X193082Y248603D01*
X193350Y248500D01*
X193618D01*
X193887Y248603D01*
X194117Y248758D01*
X194308Y248965D01*
G01X196910Y248500D02*
Y251600D01*
X195492Y249378D01*
X197408D01*
G01X198822Y249792D02*
X199090Y250153D01*
X199320Y250360D01*
X199627Y250463D01*
X199895Y250360D01*
X200087Y250153D01*
X200240Y249843D01*
X200278Y249482D01*
X200240Y249172D01*
X200087Y248862D01*
X199857Y248603D01*
X199588Y248500D01*
X199282Y248603D01*
X199013Y248913D01*
X198860Y249378D01*
X198822Y249895D01*
X198898Y250567D01*
X199013Y250928D01*
X199205Y251290D01*
X199473Y251548D01*
X199742Y251600D01*
X200010Y251497D01*
X200202Y251238D01*
G01X191983Y329000D02*
Y332100D01*
X192903D01*
X193210Y331945D01*
X193440Y331583D01*
X193517Y331170D01*
X193440Y330757D01*
X193248Y330447D01*
X192903Y330292D01*
X191983D01*
G01X196693Y331842D02*
X196463Y331997D01*
X196195Y332100D01*
X195888D01*
X195543Y331945D01*
X195275Y331687D01*
X195083Y331377D01*
X194930Y330860D01*
X194892Y330395D01*
X194968Y329930D01*
X195083Y329620D01*
X195313Y329310D01*
X195582Y329103D01*
X195850Y329000D01*
X196118D01*
X196387Y329103D01*
X196617Y329258D01*
X196808Y329465D01*
G01X199410Y329000D02*
Y332100D01*
X197992Y329878D01*
X199908D01*
G01X202510Y329000D02*
Y332100D01*
X201092Y329878D01*
X203008D01*
G01X191483Y408500D02*
Y411600D01*
X192403D01*
X192710Y411445D01*
X192940Y411083D01*
X193017Y410670D01*
X192940Y410257D01*
X192748Y409947D01*
X192403Y409792D01*
X191483D01*
G01X196193Y411342D02*
X195963Y411497D01*
X195695Y411600D01*
X195388D01*
X195043Y411445D01*
X194775Y411187D01*
X194583Y410877D01*
X194430Y410360D01*
X194392Y409895D01*
X194468Y409430D01*
X194583Y409120D01*
X194813Y408810D01*
X195082Y408603D01*
X195350Y408500D01*
X195618D01*
X195887Y408603D01*
X196117Y408758D01*
X196308Y408965D01*
G01X197607Y409120D02*
X197837Y408758D01*
X198143Y408552D01*
X198488Y408500D01*
X198795Y408552D01*
X199102Y408810D01*
X199293Y409120D01*
X199332Y409430D01*
X199255Y409792D01*
X198987Y410050D01*
X198718Y410153D01*
X198373D01*
G01X198718D02*
X198948Y410308D01*
X199140Y410567D01*
X199217Y410877D01*
X199140Y411187D01*
X198948Y411445D01*
X198603Y411600D01*
X198258Y411548D01*
X197913Y411342D01*
G01X201550Y408500D02*
X201818Y408552D01*
X202125Y408707D01*
X202317Y408965D01*
X202393Y409327D01*
X202317Y409688D01*
X202087Y409998D01*
X201742Y410153D01*
X201358D01*
X201128Y410257D01*
X200937Y410515D01*
X200860Y410877D01*
X200975Y411238D01*
X201243Y411497D01*
X201550Y411600D01*
X201857Y411497D01*
X202125Y411238D01*
X202240Y410877D01*
X202163Y410515D01*
X201972Y410257D01*
X201742Y410153D01*
X201358D01*
X201013Y409998D01*
X200783Y409688D01*
X200707Y409327D01*
X200783Y408965D01*
X200975Y408707D01*
X201282Y408552D01*
X201550Y408500D01*
G01X190983Y487500D02*
Y490600D01*
X191903D01*
X192210Y490445D01*
X192440Y490083D01*
X192517Y489670D01*
X192440Y489257D01*
X192248Y488947D01*
X191903Y488792D01*
X190983D01*
G01X195693Y490342D02*
X195463Y490497D01*
X195195Y490600D01*
X194888D01*
X194543Y490445D01*
X194275Y490187D01*
X194083Y489877D01*
X193930Y489360D01*
X193892Y488895D01*
X193968Y488430D01*
X194083Y488120D01*
X194313Y487810D01*
X194582Y487603D01*
X194850Y487500D01*
X195118D01*
X195387Y487603D01*
X195617Y487758D01*
X195808Y487965D01*
G01X197107Y488120D02*
X197337Y487758D01*
X197643Y487552D01*
X197988Y487500D01*
X198295Y487552D01*
X198602Y487810D01*
X198793Y488120D01*
X198832Y488430D01*
X198755Y488792D01*
X198487Y489050D01*
X198218Y489153D01*
X197873D01*
G01X198218D02*
X198448Y489308D01*
X198640Y489567D01*
X198717Y489877D01*
X198640Y490187D01*
X198448Y490445D01*
X198103Y490600D01*
X197758Y490548D01*
X197413Y490342D01*
G01X200322Y488792D02*
X200590Y489153D01*
X200820Y489360D01*
X201127Y489463D01*
X201395Y489360D01*
X201587Y489153D01*
X201740Y488843D01*
X201778Y488482D01*
X201740Y488172D01*
X201587Y487862D01*
X201357Y487603D01*
X201088Y487500D01*
X200782Y487603D01*
X200513Y487913D01*
X200360Y488378D01*
X200322Y488895D01*
X200398Y489567D01*
X200513Y489928D01*
X200705Y490290D01*
X200973Y490548D01*
X201242Y490600D01*
X201510Y490497D01*
X201702Y490238D01*
G01X191200Y565957D02*
Y569057D01*
X192120D01*
X192427Y568902D01*
X192657Y568540D01*
X192734Y568127D01*
X192657Y567714D01*
X192465Y567404D01*
X192120Y567249D01*
X191200D01*
G01X195910Y568799D02*
X195680Y568954D01*
X195412Y569057D01*
X195105D01*
X194760Y568902D01*
X194492Y568644D01*
X194300Y568334D01*
X194147Y567817D01*
X194109Y567352D01*
X194185Y566887D01*
X194300Y566577D01*
X194530Y566267D01*
X194799Y566060D01*
X195067Y565957D01*
X195335D01*
X195604Y566060D01*
X195834Y566215D01*
X196025Y566422D01*
G01X197324Y566577D02*
X197554Y566215D01*
X197860Y566009D01*
X198205Y565957D01*
X198512Y566009D01*
X198819Y566267D01*
X199010Y566577D01*
X199049Y566887D01*
X198972Y567249D01*
X198704Y567507D01*
X198435Y567610D01*
X198090D01*
G01X198435D02*
X198665Y567765D01*
X198857Y568024D01*
X198934Y568334D01*
X198857Y568644D01*
X198665Y568902D01*
X198320Y569057D01*
X197975Y569005D01*
X197630Y568799D01*
G01X201727Y565957D02*
Y569057D01*
X200309Y566835D01*
X202225D01*
G01X194578Y595176D02*
Y598276D01*
X195498D01*
X195805Y598121D01*
X196035Y597759D01*
X196112Y597346D01*
X196035Y596933D01*
X195843Y596623D01*
X195498Y596468D01*
X194578D01*
G01X197678Y595176D02*
Y598276D01*
X198637D01*
X198943Y598121D01*
X199135Y597914D01*
X199212Y597501D01*
X199135Y597088D01*
X198905Y596829D01*
X198637Y596674D01*
X197678D01*
G01X198637D02*
X199212Y595176D01*
G01X202312D02*
X200778D01*
Y598276D01*
X202312D01*
G01X201698Y596778D02*
X200778D01*
G01X203840Y595589D02*
X204147Y595331D01*
X204492Y595176D01*
X204798D01*
X205105Y595331D01*
X205335Y595589D01*
X205450Y595951D01*
X205373Y596313D01*
X205182Y596623D01*
X204837Y596829D01*
X204377Y596933D01*
X204108Y597139D01*
X203993Y597501D01*
X204070Y597863D01*
X204262Y598121D01*
X204530Y598276D01*
X204798D01*
X205067Y598173D01*
X205297Y597914D01*
G01X206940Y595589D02*
X207247Y595331D01*
X207592Y595176D01*
X207898D01*
X208205Y595331D01*
X208435Y595589D01*
X208550Y595951D01*
X208473Y596313D01*
X208282Y596623D01*
X207937Y596829D01*
X207477Y596933D01*
X207208Y597139D01*
X207093Y597501D01*
X207170Y597863D01*
X207362Y598121D01*
X207630Y598276D01*
X207898D01*
X208167Y598173D01*
X208397Y597914D01*
G01X210347Y596209D02*
X211343D01*
G01X213217Y595176D02*
Y598276D01*
X214673D01*
G01X214137Y596778D02*
X213217D01*
G01X216585Y598276D02*
X217505D01*
G01X217045D02*
Y595176D01*
G01X216585D02*
X217505D01*
G01X220145Y598276D02*
Y595176D01*
G01X219263Y598276D02*
X221027D01*
G01X172736Y590473D02*
Y729449D01*
G01X243012Y590473D02*
X172736D01*
G01X231201Y602283D02*
X184547D01*
Y717638D01*
X231201D01*
Y602283D01*
G01Y676496D02*
X184547D01*
G01X172736Y729449D02*
X243012D01*
G01X220611Y2100D02*
Y41595D01*
X262700D01*
G01X223133Y33500D02*
Y38500D01*
X224653D01*
X225160Y38250D01*
X225540Y37667D01*
X225667Y37000D01*
X225540Y36333D01*
X225223Y35833D01*
X224653Y35583D01*
X223133D01*
G01X228233Y33500D02*
Y38500D01*
X229817D01*
X230323Y38250D01*
X230640Y37917D01*
X230767Y37250D01*
X230640Y36583D01*
X230260Y36167D01*
X229817Y35917D01*
X228233D01*
G01X229817D02*
X230767Y33500D01*
G01X235867D02*
X233333D01*
Y38500D01*
X235867D01*
G01X234853Y36083D02*
X233333D01*
G01X238370Y34167D02*
X238877Y33750D01*
X239447Y33500D01*
X239953D01*
X240460Y33750D01*
X240840Y34167D01*
X241030Y34750D01*
X240903Y35333D01*
X240587Y35833D01*
X240017Y36167D01*
X239257Y36333D01*
X238813Y36667D01*
X238623Y37250D01*
X238750Y37833D01*
X239067Y38250D01*
X239510Y38500D01*
X239953D01*
X240397Y38333D01*
X240777Y37917D01*
G01X243470Y34167D02*
X243977Y33750D01*
X244547Y33500D01*
X245053D01*
X245560Y33750D01*
X245940Y34167D01*
X246130Y34750D01*
X246003Y35333D01*
X245687Y35833D01*
X245117Y36167D01*
X244357Y36333D01*
X243913Y36667D01*
X243723Y37250D01*
X243850Y37833D01*
X244167Y38250D01*
X244610Y38500D01*
X245053D01*
X245497Y38333D01*
X245877Y37917D01*
G01X249077Y35167D02*
X250723D01*
G01X253797Y33500D02*
Y38500D01*
X256203D01*
G01X255317Y36083D02*
X253797D01*
G01X259340Y38500D02*
X260860D01*
G01X260100D02*
Y33500D01*
G01X259340D02*
X260860D01*
G01X265200Y38500D02*
Y33500D01*
G01X263743Y38500D02*
X266657D01*
G01X241050Y81000D02*
G03I-9450J0D01*
G01X206400Y113900D02*
Y120100D01*
X209600D01*
Y113900D01*
X206400D01*
G01X209600Y107600D02*
Y101400D01*
X206400D01*
Y107600D01*
X209600D01*
G01X230585Y109327D02*
Y107087D01*
G01X232210Y108300D02*
X228960D01*
G01X230685Y110000D02*
X218441D01*
Y148000D01*
X230685D01*
G01X198883Y127500D02*
Y130600D01*
X199803D01*
X200110Y130445D01*
X200340Y130083D01*
X200417Y129670D01*
X200340Y129257D01*
X200148Y128947D01*
X199803Y128792D01*
X198883D01*
G01X202750Y127500D02*
X202443Y127552D01*
X202175Y127758D01*
X201945Y128068D01*
X201792Y128430D01*
X201715Y128843D01*
Y129257D01*
X201792Y129670D01*
X201945Y130032D01*
X202175Y130342D01*
X202443Y130548D01*
X202750Y130600D01*
X203057Y130548D01*
X203325Y130342D01*
X203555Y130032D01*
X203708Y129670D01*
X203785Y129257D01*
Y128843D01*
X203708Y128430D01*
X203555Y128068D01*
X203325Y127758D01*
X203057Y127552D01*
X202750Y127500D01*
G01X203057Y128327D02*
X203517Y127500D01*
G01X205850D02*
Y130600D01*
X205390Y129980D01*
G01Y127500D02*
X206310D01*
G01X208950D02*
X209218Y127552D01*
X209525Y127707D01*
X209717Y127965D01*
X209793Y128327D01*
X209717Y128688D01*
X209487Y128998D01*
X209142Y129153D01*
X208758D01*
X208528Y129257D01*
X208337Y129515D01*
X208260Y129877D01*
X208375Y130238D01*
X208643Y130497D01*
X208950Y130600D01*
X209257Y130497D01*
X209525Y130238D01*
X209640Y129877D01*
X209563Y129515D01*
X209372Y129257D01*
X209142Y129153D01*
X208758D01*
X208413Y128998D01*
X208183Y128688D01*
X208107Y128327D01*
X208183Y127965D01*
X208375Y127707D01*
X208682Y127552D01*
X208950Y127500D01*
G01X236185Y133500D02*
X225185D01*
G01X230685Y153713D02*
Y151287D01*
G01X242929Y149500D02*
X218441D01*
G01X242929Y148800D02*
X218441D01*
G01X242929Y148400D02*
X218441D01*
G01X242929Y149200D02*
X218441D01*
G01Y147950D02*
Y150050D01*
G01X230685Y150000D02*
X218441D01*
G01X280202Y215236D02*
G03I-36417J0D01*
G01X243785D02*
X207353D01*
X280202D01*
G01X211983Y248500D02*
Y251600D01*
X212903D01*
X213210Y251445D01*
X213440Y251083D01*
X213517Y250670D01*
X213440Y250257D01*
X213248Y249947D01*
X212903Y249792D01*
X211983D01*
G01X216693Y251342D02*
X216463Y251497D01*
X216195Y251600D01*
X215888D01*
X215543Y251445D01*
X215275Y251187D01*
X215083Y250877D01*
X214930Y250360D01*
X214892Y249895D01*
X214968Y249430D01*
X215083Y249120D01*
X215313Y248810D01*
X215582Y248603D01*
X215850Y248500D01*
X216118D01*
X216387Y248603D01*
X216617Y248758D01*
X216808Y248965D01*
G01X219410Y248500D02*
Y251600D01*
X217992Y249378D01*
X219908D01*
G01X221973Y248500D02*
X222050Y249172D01*
X222165Y249740D01*
X222318Y250257D01*
X222510Y250825D01*
X222817Y251600D01*
X221283D01*
G01X280202Y295236D02*
G03I-36417J0D01*
G01X243785D02*
X207353D01*
X280202D01*
G01X210983Y329500D02*
Y332600D01*
X211903D01*
X212210Y332445D01*
X212440Y332083D01*
X212517Y331670D01*
X212440Y331257D01*
X212248Y330947D01*
X211903Y330792D01*
X210983D01*
G01X215693Y332342D02*
X215463Y332497D01*
X215195Y332600D01*
X214888D01*
X214543Y332445D01*
X214275Y332187D01*
X214083Y331877D01*
X213930Y331360D01*
X213892Y330895D01*
X213968Y330430D01*
X214083Y330120D01*
X214313Y329810D01*
X214582Y329603D01*
X214850Y329500D01*
X215118D01*
X215387Y329603D01*
X215617Y329758D01*
X215808Y329965D01*
G01X218410Y329500D02*
Y332600D01*
X216992Y330378D01*
X218908D01*
G01X220207Y329965D02*
X220437Y329707D01*
X220705Y329552D01*
X221050Y329500D01*
X221395Y329603D01*
X221663Y329810D01*
X221855Y330172D01*
X221893Y330585D01*
X221817Y330998D01*
X221625Y331257D01*
X221357Y331463D01*
X221088Y331515D01*
X220820Y331463D01*
X220475Y331257D01*
X220590Y332600D01*
X221625D01*
G01X280202Y375236D02*
G03I-36417J0D01*
G01X243785D02*
X207353D01*
X280202D01*
G01X211983Y408500D02*
Y411600D01*
X212903D01*
X213210Y411445D01*
X213440Y411083D01*
X213517Y410670D01*
X213440Y410257D01*
X213248Y409947D01*
X212903Y409792D01*
X211983D01*
G01X216693Y411342D02*
X216463Y411497D01*
X216195Y411600D01*
X215888D01*
X215543Y411445D01*
X215275Y411187D01*
X215083Y410877D01*
X214930Y410360D01*
X214892Y409895D01*
X214968Y409430D01*
X215083Y409120D01*
X215313Y408810D01*
X215582Y408603D01*
X215850Y408500D01*
X216118D01*
X216387Y408603D01*
X216617Y408758D01*
X216808Y408965D01*
G01X218107Y409120D02*
X218337Y408758D01*
X218643Y408552D01*
X218988Y408500D01*
X219295Y408552D01*
X219602Y408810D01*
X219793Y409120D01*
X219832Y409430D01*
X219755Y409792D01*
X219487Y410050D01*
X219218Y410153D01*
X218873D01*
G01X219218D02*
X219448Y410308D01*
X219640Y410567D01*
X219717Y410877D01*
X219640Y411187D01*
X219448Y411445D01*
X219103Y411600D01*
X218758Y411548D01*
X218413Y411342D01*
G01X221398Y408862D02*
X221667Y408603D01*
X221973Y408500D01*
X222280Y408603D01*
X222548Y408913D01*
X222740Y409378D01*
X222817Y409843D01*
Y410412D01*
X222740Y410877D01*
X222548Y411290D01*
X222318Y411497D01*
X222050Y411600D01*
X221743Y411497D01*
X221513Y411290D01*
X221360Y410980D01*
X221283Y410567D01*
X221360Y410205D01*
X221552Y409843D01*
X221782Y409637D01*
X222050Y409585D01*
X222357Y409688D01*
X222587Y409947D01*
X222817Y410412D01*
G01X280202Y455236D02*
G03I-36417J0D01*
G01X243785D02*
X207353D01*
X280202D01*
G01X211983Y488000D02*
Y491100D01*
X212903D01*
X213210Y490945D01*
X213440Y490583D01*
X213517Y490170D01*
X213440Y489757D01*
X213248Y489447D01*
X212903Y489292D01*
X211983D01*
G01X216693Y490842D02*
X216463Y490997D01*
X216195Y491100D01*
X215888D01*
X215543Y490945D01*
X215275Y490687D01*
X215083Y490377D01*
X214930Y489860D01*
X214892Y489395D01*
X214968Y488930D01*
X215083Y488620D01*
X215313Y488310D01*
X215582Y488103D01*
X215850Y488000D01*
X216118D01*
X216387Y488103D01*
X216617Y488258D01*
X216808Y488465D01*
G01X218107Y488620D02*
X218337Y488258D01*
X218643Y488052D01*
X218988Y488000D01*
X219295Y488052D01*
X219602Y488310D01*
X219793Y488620D01*
X219832Y488930D01*
X219755Y489292D01*
X219487Y489550D01*
X219218Y489653D01*
X218873D01*
G01X219218D02*
X219448Y489808D01*
X219640Y490067D01*
X219717Y490377D01*
X219640Y490687D01*
X219448Y490945D01*
X219103Y491100D01*
X218758Y491048D01*
X218413Y490842D01*
G01X221973Y488000D02*
X222050Y488672D01*
X222165Y489240D01*
X222318Y489757D01*
X222510Y490325D01*
X222817Y491100D01*
X221283D01*
G01X280202Y535236D02*
G03I-36417J0D01*
G01X243785D02*
X207353D01*
X280202D01*
G01X208983Y566000D02*
Y569100D01*
X209903D01*
X210210Y568945D01*
X210440Y568583D01*
X210517Y568170D01*
X210440Y567757D01*
X210248Y567447D01*
X209903Y567292D01*
X208983D01*
G01X213693Y568842D02*
X213463Y568997D01*
X213195Y569100D01*
X212888D01*
X212543Y568945D01*
X212275Y568687D01*
X212083Y568377D01*
X211930Y567860D01*
X211892Y567395D01*
X211968Y566930D01*
X212083Y566620D01*
X212313Y566310D01*
X212582Y566103D01*
X212850Y566000D01*
X213118D01*
X213387Y566103D01*
X213617Y566258D01*
X213808Y566465D01*
G01X215107Y566620D02*
X215337Y566258D01*
X215643Y566052D01*
X215988Y566000D01*
X216295Y566052D01*
X216602Y566310D01*
X216793Y566620D01*
X216832Y566930D01*
X216755Y567292D01*
X216487Y567550D01*
X216218Y567653D01*
X215873D01*
G01X216218D02*
X216448Y567808D01*
X216640Y568067D01*
X216717Y568377D01*
X216640Y568687D01*
X216448Y568945D01*
X216103Y569100D01*
X215758Y569048D01*
X215413Y568842D01*
G01X218207Y566465D02*
X218437Y566207D01*
X218705Y566052D01*
X219050Y566000D01*
X219395Y566103D01*
X219663Y566310D01*
X219855Y566672D01*
X219893Y567085D01*
X219817Y567498D01*
X219625Y567757D01*
X219357Y567963D01*
X219088Y568015D01*
X218820Y567963D01*
X218475Y567757D01*
X218590Y569100D01*
X219625D01*
G01X206280Y579000D02*
X207547D01*
Y577500D01*
X207167Y577000D01*
X206723Y576667D01*
X206090Y576500D01*
X205457Y576667D01*
X205013Y577000D01*
X204633Y577500D01*
X204380Y578083D01*
X204253Y578750D01*
Y579333D01*
X204380Y579833D01*
X204633Y580417D01*
X205013Y580917D01*
X205393Y581250D01*
X205900Y581500D01*
X206343D01*
X206850Y581333D01*
X207230Y581000D01*
G01X209733Y576500D02*
Y581500D01*
X211253D01*
X211760Y581250D01*
X212140Y580667D01*
X212267Y580000D01*
X212140Y579333D01*
X211823Y578833D01*
X211253Y578583D01*
X209733D01*
G01X214707Y581500D02*
Y577917D01*
X214960Y577167D01*
X215467Y576667D01*
X216100Y576500D01*
X216733Y576667D01*
X217240Y577167D01*
X217493Y577917D01*
Y581500D01*
G01X225033Y576500D02*
Y581500D01*
X226553D01*
X227060Y581250D01*
X227440Y580667D01*
X227567Y580000D01*
X227440Y579333D01*
X227123Y578833D01*
X226553Y578583D01*
X225033D01*
G01X231400Y576500D02*
X230893Y576583D01*
X230450Y576917D01*
X230070Y577417D01*
X229817Y578000D01*
X229690Y578667D01*
Y579333D01*
X229817Y580000D01*
X230070Y580583D01*
X230450Y581083D01*
X230893Y581417D01*
X231400Y581500D01*
X231907Y581417D01*
X232350Y581083D01*
X232730Y580583D01*
X232983Y580000D01*
X233110Y579333D01*
Y578667D01*
X232983Y578000D01*
X232730Y577417D01*
X232350Y576917D01*
X231907Y576583D01*
X231400Y576500D01*
G01X234600Y581500D02*
X235487Y576500D01*
X236500Y581500D01*
X237513Y576500D01*
X238400Y581500D01*
G01X242867Y576500D02*
X240333D01*
Y581500D01*
X242867D01*
G01X241853Y579083D02*
X240333D01*
G01X245433Y576500D02*
Y581500D01*
X247017D01*
X247523Y581250D01*
X247840Y580917D01*
X247967Y580250D01*
X247840Y579583D01*
X247460Y579167D01*
X247017Y578917D01*
X245433D01*
G01X247017D02*
X247967Y576500D01*
G01X258293Y581083D02*
X257913Y581333D01*
X257470Y581500D01*
X256963D01*
X256393Y581250D01*
X255950Y580833D01*
X255633Y580333D01*
X255380Y579500D01*
X255317Y578750D01*
X255443Y578000D01*
X255633Y577500D01*
X256013Y577000D01*
X256457Y576667D01*
X256900Y576500D01*
X257343D01*
X257787Y576667D01*
X258167Y576917D01*
X258483Y577250D01*
G01X262000Y576500D02*
X261493Y576583D01*
X261050Y576917D01*
X260670Y577417D01*
X260417Y578000D01*
X260290Y578667D01*
Y579333D01*
X260417Y580000D01*
X260670Y580583D01*
X261050Y581083D01*
X261493Y581417D01*
X262000Y581500D01*
X262507Y581417D01*
X262950Y581083D01*
X263330Y580583D01*
X263583Y580000D01*
X263710Y579333D01*
Y578667D01*
X263583Y578000D01*
X263330Y577417D01*
X262950Y576917D01*
X262507Y576583D01*
X262000Y576500D01*
G01X265643D02*
Y581500D01*
X268557Y576500D01*
Y581500D01*
G01X270743Y576500D02*
Y581500D01*
X273657Y576500D01*
Y581500D01*
G01X202000Y583000D02*
X276000D01*
Y575000D01*
X202000D01*
Y583000D01*
G01X204383Y586120D02*
X204575Y585810D01*
X204805Y585603D01*
X205073Y585500D01*
X205380Y585603D01*
X205610Y585810D01*
X205840Y586120D01*
X205917Y586533D01*
Y588600D01*
G01X207407Y586120D02*
X207637Y585758D01*
X207943Y585552D01*
X208288Y585500D01*
X208595Y585552D01*
X208902Y585810D01*
X209093Y586120D01*
X209132Y586430D01*
X209055Y586792D01*
X208787Y587050D01*
X208518Y587153D01*
X208173D01*
G01X208518D02*
X208748Y587308D01*
X208940Y587567D01*
X209017Y587877D01*
X208940Y588187D01*
X208748Y588445D01*
X208403Y588600D01*
X208058Y588548D01*
X207713Y588342D01*
G01X254400Y-1036434D02*
X255200Y-1037100D01*
X256100Y-1037500D01*
X256900D01*
X257700Y-1037100D01*
X258300Y-1036434D01*
X258600Y-1035500D01*
X258400Y-1034567D01*
X257900Y-1033767D01*
X257000Y-1033233D01*
X255800Y-1032967D01*
X255100Y-1032433D01*
X254800Y-1031500D01*
X255000Y-1030567D01*
X255500Y-1029900D01*
X256200Y-1029500D01*
X256900D01*
X257600Y-1029767D01*
X258200Y-1030433D01*
G01X263300Y-1029500D02*
X265700D01*
G01X264500D02*
Y-1037500D01*
G01X263300D02*
X265700D01*
G01X270500Y-1029500D02*
Y-1037500D01*
X274500D01*
G01X278300D02*
Y-1029500D01*
G01X282100D02*
X278300Y-1034434D01*
G01X282700Y-1037500D02*
X280000Y-1032167D01*
G01X287200Y-1034833D02*
X289800D01*
G01X296500Y-1029500D02*
Y-1037500D01*
G01X294200Y-1029500D02*
X298800D01*
G01X304500Y-1037500D02*
X303700Y-1037367D01*
X303000Y-1036833D01*
X302400Y-1036033D01*
X302000Y-1035100D01*
X301800Y-1034033D01*
Y-1032967D01*
X302000Y-1031900D01*
X302400Y-1030967D01*
X303000Y-1030167D01*
X303700Y-1029633D01*
X304500Y-1029500D01*
X305300Y-1029633D01*
X306000Y-1030167D01*
X306600Y-1030967D01*
X307000Y-1031900D01*
X307200Y-1032967D01*
Y-1034033D01*
X307000Y-1035100D01*
X306600Y-1036033D01*
X306000Y-1036833D01*
X305300Y-1037367D01*
X304500Y-1037500D01*
G01X310500D02*
Y-1029500D01*
X312900D01*
X313700Y-1029900D01*
X314300Y-1030833D01*
X314500Y-1031900D01*
X314300Y-1032967D01*
X313800Y-1033767D01*
X312900Y-1034167D01*
X310500D01*
G01X243000Y-1004500D02*
Y-1012500D01*
X247000D01*
G01X254800D02*
Y-1007167D01*
G01Y-1008100D02*
X254400Y-1007567D01*
X253800Y-1007300D01*
X253100Y-1007167D01*
X252400Y-1007433D01*
X251800Y-1007967D01*
X251400Y-1008767D01*
X251200Y-1009833D01*
X251400Y-1010900D01*
X251800Y-1011700D01*
X252400Y-1012233D01*
X253100Y-1012500D01*
X253800Y-1012367D01*
X254400Y-1011967D01*
X254800Y-1011434D01*
G01X258900Y-1014900D02*
X259500Y-1015167D01*
X260300Y-1014900D01*
X260800Y-1014367D01*
X261200Y-1013700D01*
X261800Y-1011567D01*
X263100Y-1007167D01*
G01X259900D02*
X261800Y-1011567D01*
G01X267500Y-1008900D02*
X270700D01*
X270400Y-1007967D01*
X269900Y-1007433D01*
X269200Y-1007167D01*
X268500Y-1007300D01*
X267900Y-1007700D01*
X267500Y-1008633D01*
X267300Y-1009434D01*
Y-1010233D01*
X267500Y-1011033D01*
X268000Y-1011833D01*
X268600Y-1012367D01*
X269300Y-1012500D01*
X270000Y-1012233D01*
X270700Y-1011434D01*
G01X275600Y-1012500D02*
Y-1007167D01*
G01Y-1008233D02*
X276100Y-1007700D01*
X276600Y-1007300D01*
X277300Y-1007167D01*
X277800Y-1007300D01*
X278400Y-1007700D01*
G01X309311Y1240D02*
Y29784D01*
X232422D01*
Y1240D01*
X309311D01*
G01X227345Y93000D02*
Y96100D01*
G01X228955D02*
Y93000D01*
G01Y94550D02*
X227345D01*
G01X230522Y95583D02*
X230752Y95893D01*
X231020Y96048D01*
X231327Y96100D01*
X231710Y95997D01*
X231978Y95738D01*
X232055Y95428D01*
X232017Y95118D01*
X231863Y94860D01*
X231097Y94343D01*
X230752Y93982D01*
X230522Y93465D01*
X230445Y93000D01*
X232055D01*
G01X233507Y93465D02*
X233737Y93207D01*
X234005Y93052D01*
X234350Y93000D01*
X234695Y93103D01*
X234963Y93310D01*
X235155Y93672D01*
X235193Y94085D01*
X235117Y94498D01*
X234925Y94757D01*
X234657Y94963D01*
X234388Y95015D01*
X234120Y94963D01*
X233775Y94757D01*
X233890Y96100D01*
X234925D01*
G01X242929Y148000D02*
Y110000D01*
X230685D01*
G01X247500Y138883D02*
X244400D01*
Y139803D01*
X244555Y140110D01*
X244917Y140340D01*
X245330Y140417D01*
X245743Y140340D01*
X246053Y140148D01*
X246208Y139803D01*
Y138883D01*
G01X247500Y141907D02*
X244400D01*
Y142673D01*
X244555Y142980D01*
X244762Y143210D01*
X245072Y143402D01*
X245433Y143555D01*
X245950Y143593D01*
X246467Y143555D01*
X246828Y143402D01*
X247138Y143210D01*
X247345Y142980D01*
X247500Y142673D01*
Y141907D01*
G01Y145850D02*
X244400D01*
X245020Y145390D01*
G01X247500D02*
Y146310D01*
G01X244400Y148950D02*
X244503Y148643D01*
X244762Y148413D01*
X245072Y148260D01*
X245485Y148145D01*
X245950Y148107D01*
X246415Y148145D01*
X246828Y148260D01*
X247138Y148413D01*
X247397Y148643D01*
X247500Y148950D01*
X247397Y149257D01*
X247138Y149487D01*
X246828Y149640D01*
X246415Y149755D01*
X245950Y149793D01*
X245485Y149755D01*
X245072Y149640D01*
X244762Y149487D01*
X244503Y149257D01*
X244400Y148950D01*
G01X230685Y133500D02*
X226685Y125000D01*
X234685D01*
X230685Y133000D01*
G01Y124700D02*
Y122300D01*
G01Y133500D02*
Y136100D01*
G01X242929Y150000D02*
Y147950D01*
G01X230685Y148000D02*
X242929D01*
G01Y150000D02*
X230685D01*
G01X243012Y729449D02*
Y590473D01*
G01X245833Y594000D02*
Y599000D01*
X247353D01*
X247860Y598750D01*
X248240Y598167D01*
X248367Y597500D01*
X248240Y596833D01*
X247923Y596333D01*
X247353Y596083D01*
X245833D01*
G01X250933Y594000D02*
Y599000D01*
X252517D01*
X253023Y598750D01*
X253340Y598417D01*
X253467Y597750D01*
X253340Y597083D01*
X252960Y596667D01*
X252517Y596417D01*
X250933D01*
G01X252517D02*
X253467Y594000D01*
G01X258567D02*
X256033D01*
Y599000D01*
X258567D01*
G01X257553Y596583D02*
X256033D01*
G01X261070Y594667D02*
X261577Y594250D01*
X262147Y594000D01*
X262653D01*
X263160Y594250D01*
X263540Y594667D01*
X263730Y595250D01*
X263603Y595833D01*
X263287Y596333D01*
X262717Y596667D01*
X261957Y596833D01*
X261513Y597167D01*
X261323Y597750D01*
X261450Y598333D01*
X261767Y598750D01*
X262210Y599000D01*
X262653D01*
X263097Y598833D01*
X263477Y598417D01*
G01X266170Y594667D02*
X266677Y594250D01*
X267247Y594000D01*
X267753D01*
X268260Y594250D01*
X268640Y594667D01*
X268830Y595250D01*
X268703Y595833D01*
X268387Y596333D01*
X267817Y596667D01*
X267057Y596833D01*
X266613Y597167D01*
X266423Y597750D01*
X266550Y598333D01*
X266867Y598750D01*
X267310Y599000D01*
X267753D01*
X268197Y598833D01*
X268577Y598417D01*
G01X271777Y595667D02*
X273423D01*
G01X276497Y594000D02*
Y599000D01*
X278903D01*
G01X278017Y596583D02*
X276497D01*
G01X282040Y599000D02*
X283560D01*
G01X282800D02*
Y594000D01*
G01X282040D02*
X283560D01*
G01X287900Y599000D02*
Y594000D01*
G01X286443Y599000D02*
X289357D01*
G01X228642Y590473D02*
Y729449D01*
G01X295000Y590473D02*
X228642D01*
G01X237339Y615999D02*
X237569Y615844D01*
X237837Y615741D01*
X238144D01*
X238489Y615896D01*
X238757Y616154D01*
X238949Y616464D01*
X239102Y616981D01*
X239140Y617446D01*
X239064Y617911D01*
X238949Y618221D01*
X238719Y618531D01*
X238450Y618738D01*
X238182Y618841D01*
X237914D01*
X237645Y618738D01*
X237415Y618583D01*
X237224Y618376D01*
G01X235810Y617549D02*
X235542Y617188D01*
X235312Y616981D01*
X235005Y616878D01*
X234737Y616981D01*
X234545Y617188D01*
X234392Y617498D01*
X234354Y617859D01*
X234392Y618169D01*
X234545Y618479D01*
X234775Y618738D01*
X235044Y618841D01*
X235350Y618738D01*
X235619Y618428D01*
X235772Y617963D01*
X235810Y617446D01*
X235734Y616774D01*
X235619Y616413D01*
X235427Y616051D01*
X235159Y615793D01*
X234890Y615741D01*
X234622Y615844D01*
X234430Y616103D01*
G01X237339Y631747D02*
X237569Y631592D01*
X237837Y631489D01*
X238144D01*
X238489Y631644D01*
X238757Y631902D01*
X238949Y632212D01*
X239102Y632729D01*
X239140Y633194D01*
X239064Y633659D01*
X238949Y633969D01*
X238719Y634279D01*
X238450Y634486D01*
X238182Y634589D01*
X237914D01*
X237645Y634486D01*
X237415Y634331D01*
X237224Y634124D01*
G01X234622Y634589D02*
Y631489D01*
X236040Y633711D01*
X234124D01*
G01X237339Y623873D02*
X237569Y623718D01*
X237837Y623615D01*
X238144D01*
X238489Y623770D01*
X238757Y624028D01*
X238949Y624338D01*
X239102Y624855D01*
X239140Y625320D01*
X239064Y625785D01*
X238949Y626095D01*
X238719Y626405D01*
X238450Y626612D01*
X238182Y626715D01*
X237914D01*
X237645Y626612D01*
X237415Y626457D01*
X237224Y626250D01*
G01X235925D02*
X235695Y626508D01*
X235427Y626663D01*
X235082Y626715D01*
X234737Y626612D01*
X234469Y626405D01*
X234277Y626043D01*
X234239Y625630D01*
X234315Y625217D01*
X234507Y624958D01*
X234775Y624752D01*
X235044Y624700D01*
X235312Y624752D01*
X235657Y624958D01*
X235542Y623615D01*
X234507D01*
G01X240453Y602284D02*
X310729D01*
Y717638D01*
X240453D01*
Y602284D01*
G01X239025Y650337D02*
Y647237D01*
X238259D01*
X237952Y647392D01*
X237722Y647599D01*
X237530Y647909D01*
X237377Y648270D01*
X237339Y648787D01*
X237377Y649304D01*
X237530Y649665D01*
X237722Y649975D01*
X237952Y650182D01*
X238259Y650337D01*
X239025D01*
G01X235810Y649045D02*
X235542Y648684D01*
X235312Y648477D01*
X235005Y648374D01*
X234737Y648477D01*
X234545Y648684D01*
X234392Y648994D01*
X234354Y649355D01*
X234392Y649665D01*
X234545Y649975D01*
X234775Y650234D01*
X235044Y650337D01*
X235350Y650234D01*
X235619Y649924D01*
X235772Y649459D01*
X235810Y648942D01*
X235734Y648270D01*
X235619Y647909D01*
X235427Y647547D01*
X235159Y647289D01*
X234890Y647237D01*
X234622Y647340D01*
X234430Y647599D01*
G01X239025Y658211D02*
Y655111D01*
X238259D01*
X237952Y655266D01*
X237722Y655473D01*
X237530Y655783D01*
X237377Y656144D01*
X237339Y656661D01*
X237377Y657178D01*
X237530Y657539D01*
X237722Y657849D01*
X237952Y658056D01*
X238259Y658211D01*
X239025D01*
G01X235925Y657746D02*
X235695Y658004D01*
X235427Y658159D01*
X235082Y658211D01*
X234737Y658108D01*
X234469Y657901D01*
X234277Y657539D01*
X234239Y657126D01*
X234315Y656713D01*
X234507Y656454D01*
X234775Y656248D01*
X235044Y656196D01*
X235312Y656248D01*
X235657Y656454D01*
X235542Y655111D01*
X234507D01*
G01X239025Y666085D02*
Y662985D01*
X238259D01*
X237952Y663140D01*
X237722Y663347D01*
X237530Y663657D01*
X237377Y664018D01*
X237339Y664535D01*
X237377Y665052D01*
X237530Y665413D01*
X237722Y665723D01*
X237952Y665930D01*
X238259Y666085D01*
X239025D01*
G01X234622D02*
Y662985D01*
X236040Y665207D01*
X234124D01*
G01X240453Y676496D02*
X310729D01*
G01X228642Y729449D02*
X322540D01*
G01X262100Y-1054500D02*
X265900D01*
X262100Y-1062500D01*
X265900D01*
G01X272000Y-1057167D02*
Y-1062500D01*
G01Y-1055033D02*
X271800Y-1054900D01*
Y-1054633D01*
X272000Y-1054500D01*
X272200Y-1054633D01*
Y-1054900D01*
X272000Y-1055033D01*
G01X278700Y-1059833D02*
X281300D01*
G01X286200Y-1065167D02*
Y-1057167D01*
G01Y-1058367D02*
X286700Y-1057700D01*
X287200Y-1057300D01*
X288000Y-1057167D01*
X288700Y-1057300D01*
X289400Y-1057967D01*
X289700Y-1058900D01*
X289800Y-1059833D01*
X289700Y-1060767D01*
X289400Y-1061700D01*
X288800Y-1062233D01*
X288000Y-1062500D01*
X287300Y-1062367D01*
X286600Y-1061967D01*
X286200Y-1061434D01*
G01X296000Y-1057167D02*
Y-1062500D01*
G01Y-1055033D02*
X295800Y-1054900D01*
Y-1054633D01*
X296000Y-1054500D01*
X296200Y-1054633D01*
Y-1054900D01*
X296000Y-1055033D01*
G01X302300Y-1062500D02*
Y-1057167D01*
G01Y-1058500D02*
X302700Y-1057833D01*
X303300Y-1057300D01*
X304100Y-1057167D01*
X304800Y-1057300D01*
X305400Y-1057833D01*
X305700Y-1058767D01*
Y-1062500D01*
G01X310600Y-1064500D02*
X311300Y-1065033D01*
X312100Y-1065167D01*
X312800Y-1065033D01*
X313400Y-1064367D01*
X313800Y-1063433D01*
Y-1057167D01*
G01Y-1058233D02*
X313400Y-1057700D01*
X312800Y-1057300D01*
X312100Y-1057167D01*
X311300Y-1057433D01*
X310800Y-1057967D01*
X310400Y-1058900D01*
X310200Y-1059833D01*
X310300Y-1060633D01*
X310700Y-1061567D01*
X311300Y-1062233D01*
X312100Y-1062500D01*
X312700Y-1062367D01*
X313400Y-1061833D01*
X313800Y-1061300D01*
G01X276845Y93000D02*
Y96100D01*
G01X278455D02*
Y93000D01*
G01Y94550D02*
X276845D01*
G01X281210Y93000D02*
Y96100D01*
X279792Y93878D01*
X281708D01*
G01X313683Y44120D02*
X313875Y43810D01*
X314105Y43603D01*
X314373Y43500D01*
X314680Y43603D01*
X314910Y43810D01*
X315140Y44120D01*
X315217Y44533D01*
Y46600D01*
G01X316898Y43862D02*
X317167Y43603D01*
X317473Y43500D01*
X317780Y43603D01*
X318048Y43913D01*
X318240Y44378D01*
X318317Y44843D01*
Y45412D01*
X318240Y45877D01*
X318048Y46290D01*
X317818Y46497D01*
X317550Y46600D01*
X317243Y46497D01*
X317013Y46290D01*
X316860Y45980D01*
X316783Y45567D01*
X316860Y45205D01*
X317052Y44843D01*
X317282Y44637D01*
X317550Y44585D01*
X317857Y44688D01*
X318087Y44947D01*
X318317Y45412D01*
G01X294600Y41595D02*
X321122D01*
G01X318600Y73600D02*
Y67400D01*
X315400D01*
Y73600D01*
X318600D01*
G01X306433Y117900D02*
Y125400D01*
X308673D01*
X309420Y125025D01*
X309980Y124150D01*
X310167Y123150D01*
X309980Y122150D01*
X309513Y121400D01*
X308673Y121025D01*
X306433D01*
G01X314120Y117650D02*
X317480Y125400D01*
G01X321153Y117900D02*
Y125400D01*
X325447Y117900D01*
Y125400D01*
G01X330800Y117650D02*
X330613Y117775D01*
Y118025D01*
X330800Y118150D01*
X330987Y118025D01*
Y117775D01*
X330800Y117650D01*
G01Y121025D02*
X330613Y121150D01*
Y121400D01*
X330800Y121525D01*
X330987Y121400D01*
Y121150D01*
X330800Y121025D01*
G01X336247Y117900D02*
Y125400D01*
X338113D01*
X338860Y125025D01*
X339420Y124525D01*
X339887Y123775D01*
X340260Y122900D01*
X340353Y121650D01*
X340260Y120400D01*
X339887Y119525D01*
X339420Y118775D01*
X338860Y118275D01*
X338113Y117900D01*
X336247D01*
G01X343467D02*
X345800Y125400D01*
X348133Y117900D01*
G01X347293Y120525D02*
X344307D01*
G01X351527Y117900D02*
Y125400D01*
X355073D01*
G01X353767Y121775D02*
X351527D01*
G01X360800Y125400D02*
X360053Y125150D01*
X359493Y124525D01*
X359120Y123775D01*
X358840Y122775D01*
X358747Y121650D01*
X358840Y120525D01*
X359120Y119525D01*
X359493Y118775D01*
X360053Y118150D01*
X360800Y117900D01*
X361547Y118150D01*
X362107Y118775D01*
X362480Y119525D01*
X362760Y120525D01*
X362853Y121650D01*
X362760Y122775D01*
X362480Y123775D01*
X362107Y124525D01*
X361547Y125150D01*
X360800Y125400D01*
G01X368300D02*
Y117900D01*
G01X366153Y125400D02*
X370447D01*
G01X373933Y117900D02*
Y125400D01*
X376173D01*
X376920Y125025D01*
X377480Y124150D01*
X377667Y123150D01*
X377480Y122150D01*
X377013Y121400D01*
X376173Y121025D01*
X373933D01*
G01X384047Y121900D02*
X384420Y122275D01*
X384700Y122900D01*
X384887Y123775D01*
X384700Y124525D01*
X384327Y125025D01*
X383673Y125400D01*
X381153D01*
Y117900D01*
X384233D01*
X384887Y118400D01*
X385260Y119150D01*
X385447Y120025D01*
X385260Y120900D01*
X384700Y121650D01*
X384047Y121900D01*
X381153D01*
G01X390800Y117900D02*
Y125400D01*
X389680Y123900D01*
G01Y117900D02*
X391920D01*
G01X395967D02*
X398300Y125400D01*
X400633Y117900D01*
G01X399793Y120525D02*
X396807D01*
G01X404027Y117900D02*
Y125400D01*
X407573D01*
G01X406267Y121775D02*
X404027D01*
G01X413300Y125400D02*
X412553Y125150D01*
X411993Y124525D01*
X411620Y123775D01*
X411340Y122775D01*
X411247Y121650D01*
X411340Y120525D01*
X411620Y119525D01*
X411993Y118775D01*
X412553Y118150D01*
X413300Y117900D01*
X414047Y118150D01*
X414607Y118775D01*
X414980Y119525D01*
X415260Y120525D01*
X415353Y121650D01*
X415260Y122775D01*
X414980Y123775D01*
X414607Y124525D01*
X414047Y125150D01*
X413300Y125400D01*
G01X306500Y104900D02*
Y112900D01*
X309000D01*
X309800Y112500D01*
X310300Y111967D01*
X310500Y110900D01*
X310300Y109833D01*
X309700Y109167D01*
X309000Y108767D01*
X306500D01*
G01X309000D02*
X310500Y104900D01*
G01X315000Y108500D02*
X318200D01*
X317900Y109433D01*
X317400Y109967D01*
X316700Y110233D01*
X316000Y110100D01*
X315400Y109700D01*
X315000Y108767D01*
X314800Y107966D01*
Y107167D01*
X315000Y106367D01*
X315500Y105567D01*
X316100Y105033D01*
X316800Y104900D01*
X317500Y105167D01*
X318200Y105966D01*
G01X322700Y110233D02*
X324500Y104900D01*
X326300Y110233D01*
G01X332500Y104633D02*
X332300Y104767D01*
Y105033D01*
X332500Y105167D01*
X332700Y105033D01*
Y104767D01*
X332500Y104633D01*
G01Y108233D02*
X332300Y108367D01*
Y108633D01*
X332500Y108767D01*
X332700Y108633D01*
Y108367D01*
X332500Y108233D01*
G01X338600Y104900D02*
Y112900D01*
X342400D01*
G01X341000Y109033D02*
X338600D01*
G01X308762Y197982D02*
X309509Y197357D01*
X310349Y196982D01*
X311095D01*
X311842Y197357D01*
X312402Y197982D01*
X312682Y198857D01*
X312495Y199732D01*
X312029Y200482D01*
X311189Y200982D01*
X310069Y201232D01*
X309415Y201732D01*
X309135Y202607D01*
X309322Y203482D01*
X309789Y204107D01*
X310442Y204482D01*
X311095D01*
X311749Y204232D01*
X312309Y203607D01*
G01X316542Y196732D02*
X319902Y204482D01*
G01X323575Y196982D02*
Y204482D01*
X327869Y196982D01*
Y204482D01*
G01X306500Y184900D02*
Y178900D01*
G01D02*
X312500D01*
G01Y206459D02*
X306500D01*
G01D02*
Y200459D01*
G01Y238085D02*
Y214463D01*
X412799D01*
Y238085D01*
X306500D01*
G01X308855Y228607D02*
Y236107D01*
X311095D01*
X311842Y235732D01*
X312402Y234857D01*
X312589Y233857D01*
X312402Y232857D01*
X311935Y232107D01*
X311095Y231732D01*
X308855D01*
G01X316542Y228357D02*
X319902Y236107D01*
G01X323575Y228607D02*
Y236107D01*
X327869Y228607D01*
Y236107D01*
G01X306500Y224400D02*
Y218400D01*
G01X312500Y238085D02*
X306500D01*
G01D02*
Y232085D01*
G01X312345Y538500D02*
Y541600D01*
G01X313955D02*
Y538500D01*
G01Y540050D02*
X312345D01*
G01X315407Y539120D02*
X315637Y538758D01*
X315943Y538552D01*
X316288Y538500D01*
X316595Y538552D01*
X316902Y538810D01*
X317093Y539120D01*
X317132Y539430D01*
X317055Y539792D01*
X316787Y540050D01*
X316518Y540153D01*
X316173D01*
G01X316518D02*
X316748Y540308D01*
X316940Y540567D01*
X317017Y540877D01*
X316940Y541187D01*
X316748Y541445D01*
X316403Y541600D01*
X316058Y541548D01*
X315713Y541342D01*
G01X288883Y574920D02*
X289075Y574610D01*
X289305Y574403D01*
X289573Y574300D01*
X289880Y574403D01*
X290110Y574610D01*
X290340Y574920D01*
X290417Y575333D01*
Y577400D01*
G01X293210Y574300D02*
Y577400D01*
X291792Y575178D01*
X293708D01*
G01X310317Y626515D02*
X309650Y624015D01*
X308983Y626515D01*
G01X309223Y625640D02*
X310077D01*
G01X307957Y624432D02*
X307797Y624182D01*
X307610Y624057D01*
X307397Y624015D01*
X307130Y624098D01*
X306943Y624307D01*
X306890Y624557D01*
X306917Y624807D01*
X307023Y625015D01*
X307557Y625432D01*
X307797Y625723D01*
X307957Y626140D01*
X308010Y626515D01*
X306890D01*
G01X310317Y634389D02*
X309650Y631889D01*
X308983Y634389D01*
G01X309223Y633514D02*
X310077D01*
G01X308037Y633889D02*
X307877Y634181D01*
X307663Y634347D01*
X307423Y634389D01*
X307210Y634347D01*
X306997Y634139D01*
X306863Y633889D01*
X306837Y633639D01*
X306890Y633347D01*
X307077Y633139D01*
X307263Y633056D01*
X307503D01*
G01X307263D02*
X307103Y632931D01*
X306970Y632722D01*
X306917Y632472D01*
X306970Y632222D01*
X307103Y632014D01*
X307343Y631889D01*
X307583Y631931D01*
X307823Y632097D01*
G01X310157Y650137D02*
Y647637D01*
X309143D01*
G01X309517Y648845D02*
X310157D01*
G01X307450Y650137D02*
Y647637D01*
X307770Y648137D01*
G01Y650137D02*
X307130D01*
G01X310157Y658011D02*
Y655511D01*
X309143D01*
G01X309517Y656719D02*
X310157D01*
G01X307957Y655928D02*
X307797Y655678D01*
X307610Y655553D01*
X307397Y655511D01*
X307130Y655594D01*
X306943Y655803D01*
X306890Y656053D01*
X306917Y656303D01*
X307023Y656511D01*
X307557Y656928D01*
X307797Y657219D01*
X307957Y657636D01*
X308010Y658011D01*
X306890D01*
G01X310157Y665885D02*
Y663385D01*
X309143D01*
G01X309517Y664593D02*
X310157D01*
G01X308037Y665385D02*
X307877Y665677D01*
X307663Y665843D01*
X307423Y665885D01*
X307210Y665843D01*
X306997Y665635D01*
X306863Y665385D01*
X306837Y665135D01*
X306890Y664843D01*
X307077Y664635D01*
X307263Y664552D01*
X307503D01*
G01X307263D02*
X307103Y664427D01*
X306970Y664218D01*
X306917Y663968D01*
X306970Y663718D01*
X307103Y663510D01*
X307343Y663385D01*
X307583Y663427D01*
X307823Y663593D01*
G01X321122Y41595D02*
Y1800D01*
G01X328900Y67400D02*
Y73600D01*
X332100D01*
Y67400D01*
X328900D01*
G01X323100Y73600D02*
Y67400D01*
X319900D01*
Y73600D01*
X323100D01*
G01X324400Y67400D02*
Y73600D01*
X327600D01*
Y67400D01*
X324400D01*
G01X362510Y198400D02*
G03I-8010J0D01*
G01X342150Y188350D02*
X342250Y188550D01*
X342350Y188650D01*
X342500Y188750D01*
X342700Y188800D01*
X342950Y188750D01*
X343200Y188500D01*
X343250Y188350D01*
Y188000D01*
X343200Y187850D01*
X343100Y187700D01*
X343000Y187600D01*
X342850Y187500D01*
X342650Y187350D01*
X342500Y187150D01*
X342400Y187050D01*
X342300Y186900D01*
X342200Y186600D01*
X342150Y186250D01*
X343350D01*
G01X344300Y187950D02*
Y186250D01*
G01Y187450D02*
X344400Y187650D01*
X344500Y187800D01*
X344600Y187900D01*
X344800Y187950D01*
X344950D01*
X345150Y187900D01*
X345300Y187700D01*
X345400Y187500D01*
Y186250D01*
G01X347760Y187000D02*
G03I-710J0D01*
G01X347600Y187450D02*
X347500Y187550D01*
X347350Y187650D01*
X347200Y187700D01*
X346950D01*
X346750Y187650D01*
X346600Y187550D01*
X346450Y187400D01*
X346400Y187300D01*
X346350Y187150D01*
Y186950D01*
X346400Y186700D01*
X346500Y186550D01*
X346600Y186450D01*
X346750Y186350D01*
X346900Y186300D01*
X347100D01*
X347350Y186350D01*
X347500Y186450D01*
X347600Y186550D01*
G01X334059Y184900D02*
Y178900D01*
G01D02*
X328059D01*
G01Y206459D02*
X334059D01*
G01D02*
Y200459D01*
G01X322540Y729449D02*
Y601200D01*
G01X369600Y-1055833D02*
X370200Y-1055033D01*
X370900Y-1054633D01*
X371700Y-1054500D01*
X372700Y-1054767D01*
X373400Y-1055433D01*
X373600Y-1056233D01*
X373500Y-1057034D01*
X373100Y-1057700D01*
X371100Y-1059033D01*
X370200Y-1059967D01*
X369600Y-1061300D01*
X369400Y-1062500D01*
X373600D01*
G01X379500Y-1054500D02*
X378700Y-1054767D01*
X378100Y-1055433D01*
X377700Y-1056233D01*
X377400Y-1057300D01*
X377300Y-1058500D01*
X377400Y-1059700D01*
X377700Y-1060767D01*
X378100Y-1061567D01*
X378700Y-1062233D01*
X379500Y-1062500D01*
X380300Y-1062233D01*
X380900Y-1061567D01*
X381300Y-1060767D01*
X381600Y-1059700D01*
X381700Y-1058500D01*
X381600Y-1057300D01*
X381300Y-1056233D01*
X380900Y-1055433D01*
X380300Y-1054767D01*
X379500Y-1054500D01*
G01X385600Y-1055833D02*
X386200Y-1055033D01*
X386900Y-1054633D01*
X387700Y-1054500D01*
X388700Y-1054767D01*
X389400Y-1055433D01*
X389600Y-1056233D01*
X389500Y-1057034D01*
X389100Y-1057700D01*
X387100Y-1059033D01*
X386200Y-1059967D01*
X385600Y-1061300D01*
X385400Y-1062500D01*
X389600D01*
G01X393600Y-1055833D02*
X394200Y-1055033D01*
X394900Y-1054633D01*
X395700Y-1054500D01*
X396700Y-1054767D01*
X397400Y-1055433D01*
X397600Y-1056233D01*
X397500Y-1057034D01*
X397100Y-1057700D01*
X395100Y-1059033D01*
X394200Y-1059967D01*
X393600Y-1061300D01*
X393400Y-1062500D01*
X397600D01*
G01X401700Y-1062767D02*
X405300Y-1054500D01*
G01X411500Y-1062500D02*
Y-1054500D01*
X410300Y-1056100D01*
G01Y-1062500D02*
X412700D01*
G01X417600Y-1055833D02*
X418200Y-1055033D01*
X418900Y-1054633D01*
X419700Y-1054500D01*
X420700Y-1054767D01*
X421400Y-1055433D01*
X421600Y-1056233D01*
X421500Y-1057034D01*
X421100Y-1057700D01*
X419100Y-1059033D01*
X418200Y-1059967D01*
X417600Y-1061300D01*
X417400Y-1062500D01*
X421600D01*
G01X425700Y-1062767D02*
X429300Y-1054500D01*
G01X435500Y-1062500D02*
Y-1054500D01*
X434300Y-1056100D01*
G01Y-1062500D02*
X436700D01*
G01X441300Y-1060900D02*
X441900Y-1061833D01*
X442700Y-1062367D01*
X443600Y-1062500D01*
X444400Y-1062367D01*
X445200Y-1061700D01*
X445700Y-1060900D01*
X445800Y-1060100D01*
X445600Y-1059167D01*
X444900Y-1058500D01*
X444200Y-1058233D01*
X443300D01*
G01X444200D02*
X444800Y-1057833D01*
X445300Y-1057167D01*
X445500Y-1056367D01*
X445300Y-1055567D01*
X444800Y-1054900D01*
X443900Y-1054500D01*
X443000Y-1054633D01*
X442100Y-1055167D01*
G01X369300Y-1040000D02*
Y-1032000D01*
X371300D01*
X372100Y-1032400D01*
X372700Y-1032933D01*
X373200Y-1033733D01*
X373600Y-1034667D01*
X373700Y-1036000D01*
X373600Y-1037333D01*
X373200Y-1038267D01*
X372700Y-1039067D01*
X372100Y-1039600D01*
X371300Y-1040000D01*
X369300D01*
G01X377000D02*
X379500Y-1032000D01*
X382000Y-1040000D01*
G01X381100Y-1037200D02*
X377900D01*
G01X385600Y-1040000D02*
Y-1032000D01*
X389400D01*
G01X388000Y-1035867D02*
X385600D01*
G01X395500Y-1032000D02*
X394700Y-1032267D01*
X394100Y-1032933D01*
X393700Y-1033733D01*
X393400Y-1034800D01*
X393300Y-1036000D01*
X393400Y-1037200D01*
X393700Y-1038267D01*
X394100Y-1039067D01*
X394700Y-1039733D01*
X395500Y-1040000D01*
X396300Y-1039733D01*
X396900Y-1039067D01*
X397300Y-1038267D01*
X397600Y-1037200D01*
X397700Y-1036000D01*
X397600Y-1034800D01*
X397300Y-1033733D01*
X396900Y-1032933D01*
X396300Y-1032267D01*
X395500Y-1032000D01*
G01X403500D02*
Y-1040000D01*
G01X401200Y-1032000D02*
X405800D01*
G01X409500Y-1040000D02*
Y-1032000D01*
X411900D01*
X412700Y-1032400D01*
X413300Y-1033333D01*
X413500Y-1034400D01*
X413300Y-1035467D01*
X412800Y-1036267D01*
X411900Y-1036667D01*
X409500D01*
G01X420300Y-1035733D02*
X420700Y-1035333D01*
X421000Y-1034667D01*
X421200Y-1033733D01*
X421000Y-1032933D01*
X420600Y-1032400D01*
X419900Y-1032000D01*
X417200D01*
Y-1040000D01*
X420500D01*
X421200Y-1039467D01*
X421600Y-1038667D01*
X421800Y-1037733D01*
X421600Y-1036800D01*
X421000Y-1036000D01*
X420300Y-1035733D01*
X417200D01*
G01X427500Y-1040000D02*
Y-1032000D01*
X426300Y-1033600D01*
G01Y-1040000D02*
X428700D01*
G01X433000D02*
X435500Y-1032000D01*
X438000Y-1040000D01*
G01X437100Y-1037200D02*
X433900D01*
G01X441600Y-1040000D02*
Y-1032000D01*
X445400D01*
G01X444000Y-1035867D02*
X441600D01*
G01X451500Y-1032000D02*
X450700Y-1032267D01*
X450100Y-1032933D01*
X449700Y-1033733D01*
X449400Y-1034800D01*
X449300Y-1036000D01*
X449400Y-1037200D01*
X449700Y-1038267D01*
X450100Y-1039067D01*
X450700Y-1039733D01*
X451500Y-1040000D01*
X452300Y-1039733D01*
X452900Y-1039067D01*
X453300Y-1038267D01*
X453600Y-1037200D01*
X453700Y-1036000D01*
X453600Y-1034800D01*
X453300Y-1033733D01*
X452900Y-1032933D01*
X452300Y-1032267D01*
X451500Y-1032000D01*
G01X360700Y179400D02*
G02X353900Y174400I-6035J1083D01*
G01X348300Y179400D02*
G03X355100Y174400I6035J1083D01*
G01X354000Y184600D02*
G02X360700Y179400I585J-6163D01*
G01X349300Y204400D02*
X360300Y192900D01*
G01X355000Y184600D02*
G03X348300Y179400I-585J-6163D01*
G01X347600Y188800D02*
Y186250D01*
G01X349950Y188850D02*
Y186250D01*
G01X351450Y187950D02*
X352150Y186250D01*
X352850Y187950D01*
G01X354350Y188850D02*
Y186250D01*
G01X357250Y188000D02*
Y186250D01*
G01Y189250D02*
X357150Y189150D01*
Y189050D01*
X357250Y188950D01*
X357350Y189050D01*
Y189150D01*
X357250Y189250D01*
G01X359000Y187450D02*
X359100Y187650D01*
X359200Y187800D01*
X359300Y187900D01*
X359500Y187950D01*
X359650D01*
X359850Y187900D01*
X360000Y187700D01*
X360100Y187500D01*
Y186250D01*
G01X359000Y187950D02*
Y186250D01*
G01X361200Y187900D02*
X362100D01*
G01X361650Y188750D02*
Y186250D01*
X362350Y186300D01*
G01X364350Y187850D02*
X364200Y187900D01*
X364000Y187950D01*
X363850D01*
X363650Y187900D01*
X363550Y187850D01*
X363400Y187750D01*
X363300Y187650D01*
X363200Y187500D01*
X363150Y187400D01*
X363100Y187150D01*
Y187000D01*
X363150Y186800D01*
X363200Y186700D01*
X363300Y186550D01*
X363400Y186450D01*
X363550Y186350D01*
X363650Y186300D01*
X363900Y186250D01*
X364100D01*
X364350Y186350D01*
G01X366050Y188750D02*
Y186250D01*
X366750Y186300D01*
G01X365600Y187900D02*
X366500D01*
G01X389600Y-1012500D02*
Y-1004500D01*
X393400D01*
G01X392000Y-1008367D02*
X389600D01*
G01X399500Y-1004500D02*
X398700Y-1004767D01*
X398100Y-1005433D01*
X397700Y-1006233D01*
X397400Y-1007300D01*
X397300Y-1008500D01*
X397400Y-1009700D01*
X397700Y-1010767D01*
X398100Y-1011567D01*
X398700Y-1012233D01*
X399500Y-1012500D01*
X400300Y-1012233D01*
X400900Y-1011567D01*
X401300Y-1010767D01*
X401600Y-1009700D01*
X401700Y-1008500D01*
X401600Y-1007300D01*
X401300Y-1006233D01*
X400900Y-1005433D01*
X400300Y-1004767D01*
X399500Y-1004500D01*
G01X407500D02*
Y-1012500D01*
G01X405200Y-1004500D02*
X409800D01*
G01X412500Y-1015167D02*
X418500D01*
G01X421500Y-1012500D02*
Y-1004500D01*
X423900D01*
X424700Y-1004900D01*
X425300Y-1005833D01*
X425500Y-1006900D01*
X425300Y-1007967D01*
X424800Y-1008767D01*
X423900Y-1009167D01*
X421500D01*
G01X429300Y-1012500D02*
Y-1004500D01*
X431300D01*
X432100Y-1004900D01*
X432700Y-1005433D01*
X433200Y-1006233D01*
X433600Y-1007167D01*
X433700Y-1008500D01*
X433600Y-1009833D01*
X433200Y-1010767D01*
X432700Y-1011567D01*
X432100Y-1012100D01*
X431300Y-1012500D01*
X429300D01*
G01X440300Y-1008233D02*
X440700Y-1007833D01*
X441000Y-1007167D01*
X441200Y-1006233D01*
X441000Y-1005433D01*
X440600Y-1004900D01*
X439900Y-1004500D01*
X437200D01*
Y-1012500D01*
X440500D01*
X441200Y-1011967D01*
X441600Y-1011167D01*
X441800Y-1010233D01*
X441600Y-1009300D01*
X441000Y-1008500D01*
X440300Y-1008233D01*
X437200D01*
G01X444500Y-1015167D02*
X450500D01*
G01X456300Y-1008233D02*
X456700Y-1007833D01*
X457000Y-1007167D01*
X457200Y-1006233D01*
X457000Y-1005433D01*
X456600Y-1004900D01*
X455900Y-1004500D01*
X453200D01*
Y-1012500D01*
X456500D01*
X457200Y-1011967D01*
X457600Y-1011167D01*
X457800Y-1010233D01*
X457600Y-1009300D01*
X457000Y-1008500D01*
X456300Y-1008233D01*
X453200D01*
G01X461300Y-1012500D02*
Y-1004500D01*
X463300D01*
X464100Y-1004900D01*
X464700Y-1005433D01*
X465200Y-1006233D01*
X465600Y-1007167D01*
X465700Y-1008500D01*
X465600Y-1009833D01*
X465200Y-1010767D01*
X464700Y-1011567D01*
X464100Y-1012100D01*
X463300Y-1012500D01*
X461300D01*
G01X468500Y-1015167D02*
X474500D01*
G01X480100Y-1008500D02*
X482100D01*
Y-1010900D01*
X481500Y-1011700D01*
X480800Y-1012233D01*
X479800Y-1012500D01*
X478800Y-1012233D01*
X478100Y-1011700D01*
X477500Y-1010900D01*
X477100Y-1009967D01*
X476900Y-1008900D01*
Y-1007967D01*
X477100Y-1007167D01*
X477500Y-1006233D01*
X478100Y-1005433D01*
X478700Y-1004900D01*
X479500Y-1004500D01*
X480200D01*
X481000Y-1004767D01*
X481600Y-1005300D01*
G01X485500Y-1012500D02*
Y-1004500D01*
X487900D01*
X488700Y-1004900D01*
X489300Y-1005833D01*
X489500Y-1006900D01*
X489300Y-1007967D01*
X488800Y-1008767D01*
X487900Y-1009167D01*
X485500D01*
G01X493300Y-1004500D02*
Y-1010233D01*
X493700Y-1011434D01*
X494500Y-1012233D01*
X495500Y-1012500D01*
X496500Y-1012233D01*
X497300Y-1011434D01*
X497700Y-1010233D01*
Y-1004500D01*
G01X397300Y58800D02*
Y52200D01*
X384300D01*
Y58800D01*
X397300D01*
G01X393600Y48400D02*
Y42200D01*
X390400D01*
Y48400D01*
X393600D01*
G01X391345Y384000D02*
Y387100D01*
G01X392955D02*
Y384000D01*
G01Y385550D02*
X391345D01*
G01X394407Y384465D02*
X394637Y384207D01*
X394905Y384052D01*
X395250Y384000D01*
X395595Y384103D01*
X395863Y384310D01*
X396055Y384672D01*
X396093Y385085D01*
X396017Y385498D01*
X395825Y385757D01*
X395557Y385963D01*
X395288Y386015D01*
X395020Y385963D01*
X394675Y385757D01*
X394790Y387100D01*
X395825D01*
G01X458000Y-1065500D02*
Y-1057500D01*
X456800Y-1059100D01*
G01Y-1065500D02*
X459200D01*
G01X464100Y-1062167D02*
X464800Y-1061233D01*
X465400Y-1060700D01*
X466200Y-1060433D01*
X466900Y-1060700D01*
X467400Y-1061233D01*
X467800Y-1062033D01*
X467900Y-1062967D01*
X467800Y-1063767D01*
X467400Y-1064567D01*
X466800Y-1065233D01*
X466100Y-1065500D01*
X465300Y-1065233D01*
X464600Y-1064434D01*
X464200Y-1063233D01*
X464100Y-1061900D01*
X464300Y-1060167D01*
X464600Y-1059233D01*
X465100Y-1058300D01*
X465800Y-1057633D01*
X466500Y-1057500D01*
X467200Y-1057767D01*
X467700Y-1058433D01*
G01X474000Y-1065767D02*
X473800Y-1065633D01*
Y-1065367D01*
X474000Y-1065233D01*
X474200Y-1065367D01*
Y-1065633D01*
X474000Y-1065767D01*
G01X480100Y-1062167D02*
X480800Y-1061233D01*
X481400Y-1060700D01*
X482200Y-1060433D01*
X482900Y-1060700D01*
X483400Y-1061233D01*
X483800Y-1062033D01*
X483900Y-1062967D01*
X483800Y-1063767D01*
X483400Y-1064567D01*
X482800Y-1065233D01*
X482100Y-1065500D01*
X481300Y-1065233D01*
X480600Y-1064434D01*
X480200Y-1063233D01*
X480100Y-1061900D01*
X480300Y-1060167D01*
X480600Y-1059233D01*
X481100Y-1058300D01*
X481800Y-1057633D01*
X482500Y-1057500D01*
X483200Y-1057767D01*
X483700Y-1058433D01*
G01X459976Y58800D02*
Y52215D01*
X510235D01*
G01X459976Y78800D02*
Y65000D01*
G01X510235Y91585D02*
X459976D01*
Y85000D01*
G01X447138Y89900D02*
Y79700D01*
X442538D01*
Y89900D01*
X447138D01*
G01X459976Y123200D02*
Y109400D01*
G01Y103200D02*
Y96615D01*
X510235D01*
G01Y135985D02*
X459976D01*
Y129400D01*
G01Y147600D02*
Y141015D01*
X510235D01*
G01X447138Y134300D02*
Y124100D01*
X442538D01*
Y134300D01*
X447138D01*
G01X459976Y167600D02*
Y153800D01*
G01X510235Y180385D02*
X459976D01*
Y173800D01*
G01X447138Y178700D02*
Y168500D01*
X442538D01*
Y178700D01*
X447138D01*
G01X459976Y212000D02*
Y198200D01*
G01Y192000D02*
Y185415D01*
X510235D01*
G01Y224785D02*
X459976D01*
Y218200D01*
G01Y236400D02*
Y229815D01*
X510235D01*
G01X447138Y223100D02*
Y212900D01*
X442538D01*
Y223100D01*
X447138D01*
G01X459976Y256400D02*
Y242600D01*
G01X510235Y269185D02*
X459976D01*
Y262600D01*
G01X447138Y267500D02*
Y257300D01*
X442538D01*
Y267500D01*
X447138D01*
G01X459976Y300800D02*
Y287000D01*
G01Y280800D02*
Y274215D01*
X510235D01*
G01Y313585D02*
X459976D01*
Y307000D01*
G01X447138Y311900D02*
Y301700D01*
X442538D01*
Y311900D01*
X447138D01*
G01X487284Y319000D02*
Y332000D01*
X502284D01*
Y319000D01*
X487284D01*
G01X486883Y334500D02*
Y337600D01*
X487803D01*
X488110Y337445D01*
X488340Y337083D01*
X488417Y336670D01*
X488340Y336257D01*
X488148Y335947D01*
X487803Y335792D01*
X486883D01*
G01X490750Y334500D02*
X490443Y334552D01*
X490175Y334758D01*
X489945Y335068D01*
X489792Y335430D01*
X489715Y335843D01*
Y336257D01*
X489792Y336670D01*
X489945Y337032D01*
X490175Y337342D01*
X490443Y337548D01*
X490750Y337600D01*
X491057Y337548D01*
X491325Y337342D01*
X491555Y337032D01*
X491708Y336670D01*
X491785Y336257D01*
Y335843D01*
X491708Y335430D01*
X491555Y335068D01*
X491325Y334758D01*
X491057Y334552D01*
X490750Y334500D01*
G01X491057Y335327D02*
X491517Y334500D01*
G01X494310D02*
Y337600D01*
X492892Y335378D01*
X494808D01*
G01X497410Y334500D02*
Y337600D01*
X495992Y335378D01*
X497908D01*
G01X503000Y-1065500D02*
Y-1057500D01*
X501800Y-1059100D01*
G01Y-1065500D02*
X504200D01*
G01X510800D02*
X511000Y-1063767D01*
X511300Y-1062300D01*
X511700Y-1060967D01*
X512200Y-1059500D01*
X513000Y-1057500D01*
X509000D01*
G01X519000Y-1065767D02*
X518800Y-1065633D01*
Y-1065367D01*
X519000Y-1065233D01*
X519200Y-1065367D01*
Y-1065633D01*
X519000Y-1065767D01*
G01X525100Y-1058833D02*
X525700Y-1058033D01*
X526400Y-1057633D01*
X527200Y-1057500D01*
X528200Y-1057767D01*
X528900Y-1058433D01*
X529100Y-1059233D01*
X529000Y-1060034D01*
X528600Y-1060700D01*
X526600Y-1062033D01*
X525700Y-1062967D01*
X525100Y-1064300D01*
X524900Y-1065500D01*
X529100D01*
G01X523100Y-1040500D02*
Y-1032500D01*
X526900D01*
G01X525500Y-1036367D02*
X523100D01*
G01X520135Y52215D02*
X520212D01*
G01D02*
Y91585D01*
X520135D01*
G01X525568Y84717D02*
Y87817D01*
X526488D01*
X526795Y87662D01*
X527025Y87300D01*
X527102Y86887D01*
X527025Y86474D01*
X526833Y86164D01*
X526488Y86009D01*
X525568D01*
G01X529435Y84717D02*
X529128Y84769D01*
X528860Y84975D01*
X528630Y85285D01*
X528477Y85647D01*
X528400Y86060D01*
Y86474D01*
X528477Y86887D01*
X528630Y87249D01*
X528860Y87559D01*
X529128Y87765D01*
X529435Y87817D01*
X529742Y87765D01*
X530010Y87559D01*
X530240Y87249D01*
X530393Y86887D01*
X530470Y86474D01*
Y86060D01*
X530393Y85647D01*
X530240Y85285D01*
X530010Y84975D01*
X529742Y84769D01*
X529435Y84717D01*
G01X529742Y85544D02*
X530202Y84717D01*
G01X532995D02*
Y87817D01*
X531577Y85595D01*
X533493D01*
G01X534792Y85337D02*
X535022Y84975D01*
X535328Y84769D01*
X535673Y84717D01*
X535980Y84769D01*
X536287Y85027D01*
X536478Y85337D01*
X536517Y85647D01*
X536440Y86009D01*
X536172Y86267D01*
X535903Y86370D01*
X535558D01*
G01X535903D02*
X536133Y86525D01*
X536325Y86784D01*
X536402Y87094D01*
X536325Y87404D01*
X536133Y87662D01*
X535788Y87817D01*
X535443Y87765D01*
X535098Y87559D01*
G01X520135Y96615D02*
X520212D01*
G01D02*
Y135985D01*
X520135D01*
G01X525568Y129117D02*
Y132217D01*
X526488D01*
X526795Y132062D01*
X527025Y131700D01*
X527102Y131287D01*
X527025Y130874D01*
X526833Y130564D01*
X526488Y130409D01*
X525568D01*
G01X529435Y129117D02*
X529128Y129169D01*
X528860Y129375D01*
X528630Y129685D01*
X528477Y130047D01*
X528400Y130460D01*
Y130874D01*
X528477Y131287D01*
X528630Y131649D01*
X528860Y131959D01*
X529128Y132165D01*
X529435Y132217D01*
X529742Y132165D01*
X530010Y131959D01*
X530240Y131649D01*
X530393Y131287D01*
X530470Y130874D01*
Y130460D01*
X530393Y130047D01*
X530240Y129685D01*
X530010Y129375D01*
X529742Y129169D01*
X529435Y129117D01*
G01X529742Y129944D02*
X530202Y129117D01*
G01X532995D02*
Y132217D01*
X531577Y129995D01*
X533493D01*
G01X534907Y131700D02*
X535137Y132010D01*
X535405Y132165D01*
X535712Y132217D01*
X536095Y132114D01*
X536363Y131855D01*
X536440Y131545D01*
X536402Y131235D01*
X536248Y130977D01*
X535482Y130460D01*
X535137Y130099D01*
X534907Y129582D01*
X534830Y129117D01*
X536440D01*
G01X520135Y141015D02*
X520212D01*
G01D02*
Y180385D01*
X520135D01*
G01X525568Y173517D02*
Y176617D01*
X526488D01*
X526795Y176462D01*
X527025Y176100D01*
X527102Y175687D01*
X527025Y175274D01*
X526833Y174964D01*
X526488Y174809D01*
X525568D01*
G01X529435Y173517D02*
X529128Y173569D01*
X528860Y173775D01*
X528630Y174085D01*
X528477Y174447D01*
X528400Y174860D01*
Y175274D01*
X528477Y175687D01*
X528630Y176049D01*
X528860Y176359D01*
X529128Y176565D01*
X529435Y176617D01*
X529742Y176565D01*
X530010Y176359D01*
X530240Y176049D01*
X530393Y175687D01*
X530470Y175274D01*
Y174860D01*
X530393Y174447D01*
X530240Y174085D01*
X530010Y173775D01*
X529742Y173569D01*
X529435Y173517D01*
G01X529742Y174344D02*
X530202Y173517D01*
G01X532995D02*
Y176617D01*
X531577Y174395D01*
X533493D01*
G01X535635Y173517D02*
Y176617D01*
X535175Y175997D01*
G01Y173517D02*
X536095D01*
G01X520135Y185415D02*
X520212D01*
G01D02*
Y224785D01*
X520135D01*
G01X525568Y217917D02*
Y221017D01*
X526488D01*
X526795Y220862D01*
X527025Y220500D01*
X527102Y220087D01*
X527025Y219674D01*
X526833Y219364D01*
X526488Y219209D01*
X525568D01*
G01X529435Y217917D02*
X529128Y217969D01*
X528860Y218175D01*
X528630Y218485D01*
X528477Y218847D01*
X528400Y219260D01*
Y219674D01*
X528477Y220087D01*
X528630Y220449D01*
X528860Y220759D01*
X529128Y220965D01*
X529435Y221017D01*
X529742Y220965D01*
X530010Y220759D01*
X530240Y220449D01*
X530393Y220087D01*
X530470Y219674D01*
Y219260D01*
X530393Y218847D01*
X530240Y218485D01*
X530010Y218175D01*
X529742Y217969D01*
X529435Y217917D01*
G01X529742Y218744D02*
X530202Y217917D01*
G01X532995D02*
Y221017D01*
X531577Y218795D01*
X533493D01*
G01X535635Y221017D02*
X535328Y220914D01*
X535098Y220655D01*
X534945Y220345D01*
X534830Y219932D01*
X534792Y219467D01*
X534830Y219002D01*
X534945Y218589D01*
X535098Y218279D01*
X535328Y218020D01*
X535635Y217917D01*
X535942Y218020D01*
X536172Y218279D01*
X536325Y218589D01*
X536440Y219002D01*
X536478Y219467D01*
X536440Y219932D01*
X536325Y220345D01*
X536172Y220655D01*
X535942Y220914D01*
X535635Y221017D01*
G01X520135Y229815D02*
X520212D01*
G01D02*
Y269185D01*
X520135D01*
G01X525568Y262317D02*
Y265417D01*
X526488D01*
X526795Y265262D01*
X527025Y264900D01*
X527102Y264487D01*
X527025Y264074D01*
X526833Y263764D01*
X526488Y263609D01*
X525568D01*
G01X529435Y262317D02*
X529128Y262369D01*
X528860Y262575D01*
X528630Y262885D01*
X528477Y263247D01*
X528400Y263660D01*
Y264074D01*
X528477Y264487D01*
X528630Y264849D01*
X528860Y265159D01*
X529128Y265365D01*
X529435Y265417D01*
X529742Y265365D01*
X530010Y265159D01*
X530240Y264849D01*
X530393Y264487D01*
X530470Y264074D01*
Y263660D01*
X530393Y263247D01*
X530240Y262885D01*
X530010Y262575D01*
X529742Y262369D01*
X529435Y262317D01*
G01X529742Y263144D02*
X530202Y262317D01*
G01X531692Y262937D02*
X531922Y262575D01*
X532228Y262369D01*
X532573Y262317D01*
X532880Y262369D01*
X533187Y262627D01*
X533378Y262937D01*
X533417Y263247D01*
X533340Y263609D01*
X533072Y263867D01*
X532803Y263970D01*
X532458D01*
G01X532803D02*
X533033Y264125D01*
X533225Y264384D01*
X533302Y264694D01*
X533225Y265004D01*
X533033Y265262D01*
X532688Y265417D01*
X532343Y265365D01*
X531998Y265159D01*
G01X534983Y262679D02*
X535252Y262420D01*
X535558Y262317D01*
X535865Y262420D01*
X536133Y262730D01*
X536325Y263195D01*
X536402Y263660D01*
Y264229D01*
X536325Y264694D01*
X536133Y265107D01*
X535903Y265314D01*
X535635Y265417D01*
X535328Y265314D01*
X535098Y265107D01*
X534945Y264797D01*
X534868Y264384D01*
X534945Y264022D01*
X535137Y263660D01*
X535367Y263454D01*
X535635Y263402D01*
X535942Y263505D01*
X536172Y263764D01*
X536402Y264229D01*
G01X520135Y274215D02*
X520212D01*
G01D02*
Y313585D01*
X520135D01*
G01X525568Y306717D02*
Y309817D01*
X526488D01*
X526795Y309662D01*
X527025Y309300D01*
X527102Y308887D01*
X527025Y308474D01*
X526833Y308164D01*
X526488Y308009D01*
X525568D01*
G01X529435Y306717D02*
X529128Y306769D01*
X528860Y306975D01*
X528630Y307285D01*
X528477Y307647D01*
X528400Y308060D01*
Y308474D01*
X528477Y308887D01*
X528630Y309249D01*
X528860Y309559D01*
X529128Y309765D01*
X529435Y309817D01*
X529742Y309765D01*
X530010Y309559D01*
X530240Y309249D01*
X530393Y308887D01*
X530470Y308474D01*
Y308060D01*
X530393Y307647D01*
X530240Y307285D01*
X530010Y306975D01*
X529742Y306769D01*
X529435Y306717D01*
G01X529742Y307544D02*
X530202Y306717D01*
G01X531692Y307337D02*
X531922Y306975D01*
X532228Y306769D01*
X532573Y306717D01*
X532880Y306769D01*
X533187Y307027D01*
X533378Y307337D01*
X533417Y307647D01*
X533340Y308009D01*
X533072Y308267D01*
X532803Y308370D01*
X532458D01*
G01X532803D02*
X533033Y308525D01*
X533225Y308784D01*
X533302Y309094D01*
X533225Y309404D01*
X533033Y309662D01*
X532688Y309817D01*
X532343Y309765D01*
X531998Y309559D01*
G01X535635Y306717D02*
X535903Y306769D01*
X536210Y306924D01*
X536402Y307182D01*
X536478Y307544D01*
X536402Y307905D01*
X536172Y308215D01*
X535827Y308370D01*
X535443D01*
X535213Y308474D01*
X535022Y308732D01*
X534945Y309094D01*
X535060Y309455D01*
X535328Y309714D01*
X535635Y309817D01*
X535942Y309714D01*
X536210Y309455D01*
X536325Y309094D01*
X536248Y308732D01*
X536057Y308474D01*
X535827Y308370D01*
X535443D01*
X535098Y308215D01*
X534868Y307905D01*
X534792Y307544D01*
X534868Y307182D01*
X535060Y306924D01*
X535367Y306769D01*
X535635Y306717D01*
G01X510334Y330600D02*
X516534D01*
Y327400D01*
X510334D01*
Y330600D01*
G01X507184D02*
X513384D01*
Y327400D01*
X507184D01*
Y330600D01*
G01Y323600D02*
X513384D01*
Y320400D01*
X507184D01*
Y323600D01*
G01X516534Y320400D02*
X510334D01*
Y323600D01*
X516534D01*
Y320400D01*
G01X578707Y130400D02*
Y102200D01*
X547307D01*
Y130400D01*
X578707D01*
G01X549230Y137600D02*
X559430D01*
Y133000D01*
X549230D01*
Y137600D01*
G01X559430Y140000D02*
X549230D01*
Y144600D01*
X559430D01*
Y140000D01*
G01Y147000D02*
X549230D01*
Y151600D01*
X559430D01*
Y147000D01*
G01X578707Y263600D02*
Y235400D01*
X547307D01*
Y263600D01*
X578707D01*
G01X559430Y266200D02*
X549230D01*
Y270800D01*
X559430D01*
Y266200D01*
G01Y280200D02*
X549230D01*
Y284800D01*
X559430D01*
Y280200D01*
G01Y273200D02*
X549230D01*
Y277800D01*
X559430D01*
Y273200D01*
G01X598018Y480176D02*
Y477076D01*
X597098D01*
X596791Y477231D01*
X596561Y477593D01*
X596484Y478006D01*
X596561Y478419D01*
X596753Y478729D01*
X597098Y478884D01*
X598018D01*
G01X594841Y480279D02*
X593461Y477076D01*
G01X591933Y480176D02*
Y477076D01*
X590169Y480176D01*
Y477076D01*
G01X587951Y480279D02*
X588028Y480228D01*
Y480124D01*
X587951Y480073D01*
X587874Y480124D01*
Y480228D01*
X587951Y480279D01*
G01Y478884D02*
X588028Y478833D01*
Y478729D01*
X587951Y478678D01*
X587874Y478729D01*
Y478833D01*
X587951Y478884D01*
G01X585694Y480176D02*
Y477076D01*
X584928D01*
X584621Y477231D01*
X584391Y477438D01*
X584199Y477748D01*
X584046Y478109D01*
X584008Y478626D01*
X584046Y479143D01*
X584199Y479504D01*
X584391Y479814D01*
X584621Y480021D01*
X584928Y480176D01*
X585694D01*
G01X582709D02*
X581751Y477076D01*
X580793Y480176D01*
G01X581138Y479091D02*
X582364D01*
G01X579379Y480176D02*
Y477076D01*
X577923D01*
G01X578459Y478574D02*
X579379D01*
G01X575551Y477076D02*
X575858Y477179D01*
X576088Y477438D01*
X576241Y477748D01*
X576356Y478161D01*
X576394Y478626D01*
X576356Y479091D01*
X576241Y479504D01*
X576088Y479814D01*
X575858Y480073D01*
X575551Y480176D01*
X575244Y480073D01*
X575014Y479814D01*
X574861Y479504D01*
X574746Y479091D01*
X574708Y478626D01*
X574746Y478161D01*
X574861Y477748D01*
X575014Y477438D01*
X575244Y477179D01*
X575551Y477076D01*
G01X572451D02*
Y480176D01*
G01X573333Y477076D02*
X571569D01*
G01X570118Y480176D02*
Y477076D01*
X569198D01*
X568891Y477231D01*
X568661Y477593D01*
X568584Y478006D01*
X568661Y478419D01*
X568853Y478729D01*
X569198Y478884D01*
X570118D01*
G01X565944Y478523D02*
X565791Y478368D01*
X565676Y478109D01*
X565599Y477748D01*
X565676Y477438D01*
X565829Y477231D01*
X566098Y477076D01*
X567133D01*
Y480176D01*
X565868D01*
X565599Y479969D01*
X565446Y479659D01*
X565369Y479298D01*
X565446Y478936D01*
X565676Y478626D01*
X565944Y478523D01*
X567133D01*
G01X563151Y480176D02*
Y477076D01*
X563611Y477696D01*
G01Y480176D02*
X562691D01*
G01X561009D02*
X560051Y477076D01*
X559093Y480176D01*
G01X559438Y479091D02*
X560664D01*
G01X557679Y480176D02*
Y477076D01*
X556223D01*
G01X556759Y478574D02*
X557679D01*
G01X553851Y477076D02*
X554158Y477179D01*
X554388Y477438D01*
X554541Y477748D01*
X554656Y478161D01*
X554694Y478626D01*
X554656Y479091D01*
X554541Y479504D01*
X554388Y479814D01*
X554158Y480073D01*
X553851Y480176D01*
X553544Y480073D01*
X553314Y479814D01*
X553161Y479504D01*
X553046Y479091D01*
X553008Y478626D01*
X553046Y478161D01*
X553161Y477748D01*
X553314Y477438D01*
X553544Y477179D01*
X553851Y477076D01*
G01X561583Y96450D02*
Y99550D01*
X562503D01*
X562810Y99395D01*
X563040Y99033D01*
X563117Y98620D01*
X563040Y98207D01*
X562848Y97897D01*
X562503Y97742D01*
X561583D01*
G01X564683Y96450D02*
Y99550D01*
X565642D01*
X565948Y99395D01*
X566140Y99188D01*
X566217Y98775D01*
X566140Y98362D01*
X565910Y98103D01*
X565642Y97948D01*
X564683D01*
G01X565642D02*
X566217Y96450D01*
G01X567822Y97742D02*
X568090Y98103D01*
X568320Y98310D01*
X568627Y98413D01*
X568895Y98310D01*
X569087Y98103D01*
X569240Y97793D01*
X569278Y97432D01*
X569240Y97122D01*
X569087Y96812D01*
X568857Y96553D01*
X568588Y96450D01*
X568282Y96553D01*
X568013Y96863D01*
X567860Y97328D01*
X567822Y97845D01*
X567898Y98517D01*
X568013Y98878D01*
X568205Y99240D01*
X568473Y99498D01*
X568742Y99550D01*
X569010Y99447D01*
X569202Y99188D01*
G01X570998Y96812D02*
X571267Y96553D01*
X571573Y96450D01*
X571880Y96553D01*
X572148Y96863D01*
X572340Y97328D01*
X572417Y97793D01*
Y98362D01*
X572340Y98827D01*
X572148Y99240D01*
X571918Y99447D01*
X571650Y99550D01*
X571343Y99447D01*
X571113Y99240D01*
X570960Y98930D01*
X570883Y98517D01*
X570960Y98155D01*
X571152Y97793D01*
X571382Y97587D01*
X571650Y97535D01*
X571957Y97638D01*
X572187Y97897D01*
X572417Y98362D01*
G01X574750Y96450D02*
X575018Y96502D01*
X575325Y96657D01*
X575517Y96915D01*
X575593Y97277D01*
X575517Y97638D01*
X575287Y97948D01*
X574942Y98103D01*
X574558D01*
X574328Y98207D01*
X574137Y98465D01*
X574060Y98827D01*
X574175Y99188D01*
X574443Y99447D01*
X574750Y99550D01*
X575057Y99447D01*
X575325Y99188D01*
X575440Y98827D01*
X575363Y98465D01*
X575172Y98207D01*
X574942Y98103D01*
X574558D01*
X574213Y97948D01*
X573983Y97638D01*
X573907Y97277D01*
X573983Y96915D01*
X574175Y96657D01*
X574482Y96502D01*
X574750Y96450D01*
G01X577198Y96812D02*
X577467Y96553D01*
X577773Y96450D01*
X578080Y96553D01*
X578348Y96863D01*
X578540Y97328D01*
X578617Y97793D01*
Y98362D01*
X578540Y98827D01*
X578348Y99240D01*
X578118Y99447D01*
X577850Y99550D01*
X577543Y99447D01*
X577313Y99240D01*
X577160Y98930D01*
X577083Y98517D01*
X577160Y98155D01*
X577352Y97793D01*
X577582Y97587D01*
X577850Y97535D01*
X578157Y97638D01*
X578387Y97897D01*
X578617Y98362D01*
G01X576430Y133000D02*
X566230D01*
Y137600D01*
X576430D01*
Y133000D01*
G01X566230Y144600D02*
X576430D01*
Y140000D01*
X566230D01*
Y144600D01*
G01Y151600D02*
X576430D01*
Y147000D01*
X566230D01*
Y151600D01*
G01X565830Y153700D02*
X559630D01*
Y156900D01*
X565830D01*
Y153700D01*
G01X561583Y230450D02*
Y233550D01*
X562503D01*
X562810Y233395D01*
X563040Y233033D01*
X563117Y232620D01*
X563040Y232207D01*
X562848Y231897D01*
X562503Y231742D01*
X561583D01*
G01X564683Y230450D02*
Y233550D01*
X565642D01*
X565948Y233395D01*
X566140Y233188D01*
X566217Y232775D01*
X566140Y232362D01*
X565910Y232103D01*
X565642Y231948D01*
X564683D01*
G01X565642D02*
X566217Y230450D01*
G01X567822Y231742D02*
X568090Y232103D01*
X568320Y232310D01*
X568627Y232413D01*
X568895Y232310D01*
X569087Y232103D01*
X569240Y231793D01*
X569278Y231432D01*
X569240Y231122D01*
X569087Y230812D01*
X568857Y230553D01*
X568588Y230450D01*
X568282Y230553D01*
X568013Y230863D01*
X567860Y231328D01*
X567822Y231845D01*
X567898Y232517D01*
X568013Y232878D01*
X568205Y233240D01*
X568473Y233498D01*
X568742Y233550D01*
X569010Y233447D01*
X569202Y233188D01*
G01X570998Y230812D02*
X571267Y230553D01*
X571573Y230450D01*
X571880Y230553D01*
X572148Y230863D01*
X572340Y231328D01*
X572417Y231793D01*
Y232362D01*
X572340Y232827D01*
X572148Y233240D01*
X571918Y233447D01*
X571650Y233550D01*
X571343Y233447D01*
X571113Y233240D01*
X570960Y232930D01*
X570883Y232517D01*
X570960Y232155D01*
X571152Y231793D01*
X571382Y231587D01*
X571650Y231535D01*
X571957Y231638D01*
X572187Y231897D01*
X572417Y232362D01*
G01X574673Y230450D02*
X574750Y231122D01*
X574865Y231690D01*
X575018Y232207D01*
X575210Y232775D01*
X575517Y233550D01*
X573983D01*
G01X577122Y231742D02*
X577390Y232103D01*
X577620Y232310D01*
X577927Y232413D01*
X578195Y232310D01*
X578387Y232103D01*
X578540Y231793D01*
X578578Y231432D01*
X578540Y231122D01*
X578387Y230812D01*
X578157Y230553D01*
X577888Y230450D01*
X577582Y230553D01*
X577313Y230863D01*
X577160Y231328D01*
X577122Y231845D01*
X577198Y232517D01*
X577313Y232878D01*
X577505Y233240D01*
X577773Y233498D01*
X578042Y233550D01*
X578310Y233447D01*
X578502Y233188D01*
G01X566230Y270800D02*
X576430D01*
Y266200D01*
X566230D01*
Y270800D01*
G01X565830Y285900D02*
X559630D01*
Y289100D01*
X565830D01*
Y285900D01*
G01X566230Y284800D02*
X576430D01*
Y280200D01*
X566230D01*
Y284800D01*
G01Y277800D02*
X576430D01*
Y273200D01*
X566230D01*
Y277800D01*
G01X588000Y314700D02*
Y321300D01*
X601000D01*
Y314700D01*
X588000D01*
G01X606100Y298400D02*
X599900D01*
Y301600D01*
X606100D01*
Y298400D01*
G01X649100Y249200D02*
X638900D01*
Y253800D01*
X649100D01*
Y249200D01*
G01X647900Y255900D02*
Y262100D01*
X651100D01*
Y255900D01*
X647900D01*
G01X627700Y324000D02*
X634300D01*
Y311000D01*
X627700D01*
Y324000D01*
G01X637733Y314807D02*
X639955D01*
X640420Y314960D01*
X640730Y315267D01*
X640833Y315650D01*
X640730Y316033D01*
X640420Y316340D01*
X639955Y316493D01*
X637733D01*
G01X640833Y319210D02*
X637733D01*
X639955Y317792D01*
Y319708D01*
G01X640833Y322310D02*
X637733D01*
X639955Y320892D01*
Y322808D01*
G01X642169Y326512D02*
Y315488D01*
G01Y326512D02*
X650831D01*
Y315488D01*
X642169D01*
G01X669702Y185100D02*
Y182878D01*
X669855Y182413D01*
X670162Y182103D01*
X670545Y182000D01*
X670928Y182103D01*
X671235Y182413D01*
X671388Y182878D01*
Y185100D01*
G01X672917Y184583D02*
X673147Y184893D01*
X673415Y185048D01*
X673722Y185100D01*
X674105Y184997D01*
X674373Y184738D01*
X674450Y184428D01*
X674412Y184118D01*
X674258Y183860D01*
X673492Y183343D01*
X673147Y182982D01*
X672917Y182465D01*
X672840Y182000D01*
X674450D01*
G01X675902Y182620D02*
X676132Y182258D01*
X676438Y182052D01*
X676783Y182000D01*
X677090Y182052D01*
X677397Y182310D01*
X677588Y182620D01*
X677627Y182930D01*
X677550Y183292D01*
X677282Y183550D01*
X677013Y183653D01*
X676668D01*
G01X677013D02*
X677243Y183808D01*
X677435Y184067D01*
X677512Y184377D01*
X677435Y184687D01*
X677243Y184945D01*
X676898Y185100D01*
X676553Y185048D01*
X676208Y184842D01*
G01X692412Y193906D02*
Y182094D01*
X679788D01*
Y193906D01*
X692412D01*
G01X668284Y254400D02*
X662084D01*
Y257600D01*
X668284D01*
Y254400D01*
G01X658784Y249900D02*
X652584D01*
Y253100D01*
X658784D01*
Y249900D01*
G01Y254400D02*
X652584D01*
Y257600D01*
X658784D01*
Y254400D01*
G01X662084Y262100D02*
X668284D01*
Y258900D01*
X662084D01*
Y262100D01*
G01Y266100D02*
X668284D01*
Y262900D01*
X662084D01*
Y266100D01*
G01X658784Y258900D02*
X652584D01*
Y262100D01*
X658784D01*
Y258900D01*
G01Y264400D02*
X652584D01*
Y267600D01*
X658784D01*
Y264400D01*
G01X668284Y249900D02*
X662084D01*
Y253100D01*
X668284D01*
Y249900D01*
G01X682200Y296900D02*
X676000D01*
Y300100D01*
X682200D01*
Y296900D01*
G01X670300Y323100D02*
Y312900D01*
X665700D01*
Y323100D01*
X670300D01*
G01X676000Y304100D02*
X682200D01*
Y300900D01*
X676000D01*
Y304100D01*
G01X665100Y319100D02*
Y312900D01*
X661900D01*
Y319100D01*
X665100D01*
G01X663600Y320900D02*
X657400D01*
Y324100D01*
X663600D01*
Y320900D01*
G01X651900Y325400D02*
Y331600D01*
X655100D01*
Y325400D01*
X651900D01*
G01X679000Y323000D02*
X676398Y325602D01*
X672176D01*
Y313398D01*
X685824D01*
Y325602D01*
X681602D01*
X679000Y323000D01*
G01X674900Y330400D02*
Y336600D01*
X678100D01*
Y330400D01*
X674900D01*
G01X678900D02*
Y336600D01*
X682100D01*
Y330400D01*
X678900D01*
G01X687098Y583155D02*
Y556929D01*
X652522Y570042D01*
X687098Y583155D01*
G01X707000Y181300D02*
Y174700D01*
X694000D01*
Y181300D01*
X707000D01*
G01X693100Y176900D02*
X686900D01*
Y180100D01*
X693100D01*
Y176900D01*
G01X709307Y200100D02*
Y197878D01*
X709460Y197413D01*
X709767Y197103D01*
X710150Y197000D01*
X710533Y197103D01*
X710840Y197413D01*
X710993Y197878D01*
Y200100D01*
G01X712522Y199583D02*
X712752Y199893D01*
X713020Y200048D01*
X713327Y200100D01*
X713710Y199997D01*
X713978Y199738D01*
X714055Y199428D01*
X714017Y199118D01*
X713863Y198860D01*
X713097Y198343D01*
X712752Y197982D01*
X712522Y197465D01*
X712445Y197000D01*
X714055D01*
G01X715507Y197465D02*
X715737Y197207D01*
X716005Y197052D01*
X716350Y197000D01*
X716695Y197103D01*
X716963Y197310D01*
X717155Y197672D01*
X717193Y198085D01*
X717117Y198498D01*
X716925Y198757D01*
X716657Y198963D01*
X716388Y199015D01*
X716120Y198963D01*
X715775Y198757D01*
X715890Y200100D01*
X716925D01*
G01X707412Y199406D02*
Y187594D01*
X694788D01*
Y199406D01*
X707412D01*
G01X690500Y257100D02*
X696700D01*
Y253900D01*
X690500D01*
Y257100D01*
G01Y253100D02*
X696700D01*
Y249900D01*
X690500D01*
Y253100D01*
G01X683057Y330050D02*
Y327828D01*
X683210Y327363D01*
X683517Y327053D01*
X683900Y326950D01*
X684283Y327053D01*
X684590Y327363D01*
X684743Y327828D01*
Y330050D01*
G01X686157Y327570D02*
X686387Y327208D01*
X686693Y327002D01*
X687038Y326950D01*
X687345Y327002D01*
X687652Y327260D01*
X687843Y327570D01*
X687882Y327880D01*
X687805Y328242D01*
X687537Y328500D01*
X687268Y328603D01*
X686923D01*
G01X687268D02*
X687498Y328758D01*
X687690Y329017D01*
X687767Y329327D01*
X687690Y329637D01*
X687498Y329895D01*
X687153Y330050D01*
X686808Y329998D01*
X686463Y329792D01*
G01X689257Y327415D02*
X689487Y327157D01*
X689755Y327002D01*
X690100Y326950D01*
X690445Y327053D01*
X690713Y327260D01*
X690905Y327622D01*
X690943Y328035D01*
X690867Y328448D01*
X690675Y328707D01*
X690407Y328913D01*
X690138Y328965D01*
X689870Y328913D01*
X689525Y328707D01*
X689640Y330050D01*
X690675D01*
G01X691380Y557883D02*
X691690Y558075D01*
X691897Y558305D01*
X692000Y558573D01*
X691897Y558880D01*
X691690Y559110D01*
X691380Y559340D01*
X690967Y559417D01*
X688900D01*
G01X692000Y561750D02*
X688900D01*
X689520Y561290D01*
G01X692000D02*
Y562210D01*
G01X689417Y564122D02*
X689107Y564352D01*
X688952Y564620D01*
X688900Y564927D01*
X689003Y565310D01*
X689262Y565578D01*
X689572Y565655D01*
X689882Y565617D01*
X690140Y565463D01*
X690657Y564697D01*
X691018Y564352D01*
X691535Y564122D01*
X692000Y564045D01*
Y565655D01*
G01X731911Y298995D02*
X725711D01*
Y302195D01*
X731911D01*
Y298995D01*
G01X733600Y312100D02*
Y305900D01*
X730400D01*
Y312100D01*
X733600D01*
G01X719057Y323550D02*
Y321328D01*
X719210Y320863D01*
X719517Y320553D01*
X719900Y320450D01*
X720283Y320553D01*
X720590Y320863D01*
X720743Y321328D01*
Y323550D01*
G01X723460Y320450D02*
Y323550D01*
X722042Y321328D01*
X723958D01*
G01X725257Y320915D02*
X725487Y320657D01*
X725755Y320502D01*
X726100Y320450D01*
X726445Y320553D01*
X726713Y320760D01*
X726905Y321122D01*
X726943Y321535D01*
X726867Y321948D01*
X726675Y322207D01*
X726407Y322413D01*
X726138Y322465D01*
X725870Y322413D01*
X725525Y322207D01*
X725640Y323550D01*
X726675D01*
G01X727331Y303488D02*
Y314512D01*
G01Y303488D02*
X718669D01*
Y314512D01*
X727331D01*
G01X745845Y42000D02*
Y45100D01*
G01X747455D02*
Y42000D01*
G01Y43550D02*
X745845D01*
G01X749673Y42000D02*
X749750Y42672D01*
X749865Y43240D01*
X750018Y43757D01*
X750210Y44325D01*
X750517Y45100D01*
X748983D01*
G01X847559Y65689D02*
X766536D01*
Y336279D01*
X847559D01*
Y65689D01*
G01X775737Y169067D02*
X768237D01*
Y171307D01*
X768612Y172054D01*
X769487Y172614D01*
X770487Y172801D01*
X771487Y172614D01*
X772237Y172147D01*
X772612Y171307D01*
Y169067D01*
G01X775737Y176567D02*
X768237D01*
Y178901D01*
X768612Y179647D01*
X769112Y180114D01*
X770112Y180301D01*
X771112Y180114D01*
X771737Y179554D01*
X772112Y178901D01*
Y176567D01*
G01Y178901D02*
X775737Y180301D01*
G01Y187801D02*
Y184067D01*
X768237D01*
Y187801D01*
G01X771862Y186307D02*
Y184067D01*
G01X774737Y191474D02*
X775362Y192221D01*
X775737Y193061D01*
Y193807D01*
X775362Y194554D01*
X774737Y195114D01*
X773862Y195394D01*
X772987Y195207D01*
X772237Y194741D01*
X771737Y193901D01*
X771487Y192781D01*
X770987Y192127D01*
X770112Y191847D01*
X769237Y192034D01*
X768612Y192501D01*
X768237Y193154D01*
Y193807D01*
X768487Y194461D01*
X769112Y195021D01*
G01X774737Y198974D02*
X775362Y199721D01*
X775737Y200561D01*
Y201307D01*
X775362Y202054D01*
X774737Y202614D01*
X773862Y202894D01*
X772987Y202707D01*
X772237Y202241D01*
X771737Y201401D01*
X771487Y200281D01*
X770987Y199627D01*
X770112Y199347D01*
X769237Y199534D01*
X768612Y200001D01*
X768237Y200654D01*
Y201307D01*
X768487Y201961D01*
X769112Y202521D01*
G01X773237Y207221D02*
Y209647D01*
G01X775737Y214161D02*
X768237D01*
Y217707D01*
G01X771862Y216401D02*
Y214161D01*
G01X768237Y222314D02*
Y224554D01*
G01Y223434D02*
X775737D01*
G01Y222314D02*
Y224554D01*
G01X768237Y230934D02*
X775737D01*
G01X768237Y228787D02*
Y233081D01*
G01X745845Y321500D02*
Y324600D01*
G01X747455D02*
Y321500D01*
G01Y323050D02*
X745845D01*
G01X749022Y322792D02*
X749290Y323153D01*
X749520Y323360D01*
X749827Y323463D01*
X750095Y323360D01*
X750287Y323153D01*
X750440Y322843D01*
X750478Y322482D01*
X750440Y322172D01*
X750287Y321862D01*
X750057Y321603D01*
X749788Y321500D01*
X749482Y321603D01*
X749213Y321913D01*
X749060Y322378D01*
X749022Y322895D01*
X749098Y323567D01*
X749213Y323928D01*
X749405Y324290D01*
X749673Y324548D01*
X749942Y324600D01*
X750210Y324497D01*
X750402Y324238D01*
G01X765170Y383000D02*
Y388000D01*
G01X767830D02*
Y383000D01*
G01Y385500D02*
X765170D01*
G01X770270Y383667D02*
X770777Y383250D01*
X771347Y383000D01*
X771853D01*
X772360Y383250D01*
X772740Y383667D01*
X772930Y384250D01*
X772803Y384833D01*
X772487Y385333D01*
X771917Y385667D01*
X771157Y385833D01*
X770713Y386167D01*
X770523Y386750D01*
X770650Y387333D01*
X770967Y387750D01*
X771410Y388000D01*
X771853D01*
X772297Y387833D01*
X772677Y387417D01*
G01X778093Y387583D02*
X777713Y387833D01*
X777270Y388000D01*
X776763D01*
X776193Y387750D01*
X775750Y387333D01*
X775433Y386833D01*
X775180Y386000D01*
X775117Y385250D01*
X775243Y384500D01*
X775433Y384000D01*
X775813Y383500D01*
X776257Y383167D01*
X776700Y383000D01*
X777143D01*
X777587Y383167D01*
X777967Y383417D01*
X778283Y383750D01*
G01X780597Y387167D02*
X780977Y387667D01*
X781420Y387917D01*
X781927Y388000D01*
X782560Y387833D01*
X783003Y387417D01*
X783130Y386917D01*
X783067Y386417D01*
X782813Y386000D01*
X781547Y385167D01*
X780977Y384583D01*
X780597Y383750D01*
X780470Y383000D01*
X783130D01*
G01X793267D02*
X790733D01*
Y388000D01*
X793267D01*
G01X792253Y385583D02*
X790733D01*
G01X795643Y383000D02*
Y388000D01*
X798557Y383000D01*
Y388000D01*
G01X800617Y383000D02*
X802200Y388000D01*
X803783Y383000D01*
G01X803213Y384750D02*
X801187D01*
G01X807807Y385667D02*
X808060Y385917D01*
X808250Y386333D01*
X808377Y386917D01*
X808250Y387417D01*
X807997Y387750D01*
X807553Y388000D01*
X805843D01*
Y383000D01*
X807933D01*
X808377Y383333D01*
X808630Y383833D01*
X808757Y384417D01*
X808630Y385000D01*
X808250Y385500D01*
X807807Y385667D01*
X805843D01*
G01X811133Y388000D02*
Y383000D01*
X813667D01*
G01X818767D02*
X816233D01*
Y388000D01*
X818767D01*
G01X817753Y385583D02*
X816233D01*
G01X768250Y377000D02*
Y380100D01*
X767790Y379480D01*
G01Y377000D02*
X768710D01*
G01X770852Y378033D02*
X771848D01*
G01X773722Y379583D02*
X773952Y379893D01*
X774220Y380048D01*
X774527Y380100D01*
X774910Y379997D01*
X775178Y379738D01*
X775255Y379428D01*
X775217Y379118D01*
X775063Y378860D01*
X774297Y378343D01*
X773952Y377982D01*
X773722Y377465D01*
X773645Y377000D01*
X775255D01*
G01X779807D02*
Y380100D01*
X780573D01*
X780880Y379945D01*
X781110Y379738D01*
X781302Y379428D01*
X781455Y379067D01*
X781493Y378550D01*
X781455Y378033D01*
X781302Y377672D01*
X781110Y377362D01*
X780880Y377155D01*
X780573Y377000D01*
X779807D01*
G01X783290Y380100D02*
X784210D01*
G01X783750D02*
Y377000D01*
G01X783290D02*
X784210D01*
G01X786045Y377413D02*
X786352Y377155D01*
X786697Y377000D01*
X787003D01*
X787310Y377155D01*
X787540Y377413D01*
X787655Y377775D01*
X787578Y378137D01*
X787387Y378447D01*
X787042Y378653D01*
X786582Y378757D01*
X786313Y378963D01*
X786198Y379325D01*
X786275Y379687D01*
X786467Y379945D01*
X786735Y380100D01*
X787003D01*
X787272Y379997D01*
X787502Y379738D01*
G01X788992Y377000D02*
X789950Y380100D01*
X790908Y377000D01*
G01X790563Y378085D02*
X789337D01*
G01X793357Y378653D02*
X793510Y378808D01*
X793625Y379067D01*
X793702Y379428D01*
X793625Y379738D01*
X793472Y379945D01*
X793203Y380100D01*
X792168D01*
Y377000D01*
X793433D01*
X793702Y377207D01*
X793855Y377517D01*
X793932Y377878D01*
X793855Y378240D01*
X793625Y378550D01*
X793357Y378653D01*
X792168D01*
G01X795383Y380100D02*
Y377000D01*
X796917D01*
G01X800017D02*
X798483D01*
Y380100D01*
X800017D01*
G01X799403Y378602D02*
X798483D01*
G01X767522Y374083D02*
X767752Y374393D01*
X768020Y374548D01*
X768327Y374600D01*
X768710Y374497D01*
X768978Y374238D01*
X769055Y373928D01*
X769017Y373618D01*
X768863Y373360D01*
X768097Y372843D01*
X767752Y372482D01*
X767522Y371965D01*
X767445Y371500D01*
X769055D01*
G01X770852Y372533D02*
X771848D01*
G01X773607Y372120D02*
X773837Y371758D01*
X774143Y371552D01*
X774488Y371500D01*
X774795Y371552D01*
X775102Y371810D01*
X775293Y372120D01*
X775332Y372430D01*
X775255Y372792D01*
X774987Y373050D01*
X774718Y373153D01*
X774373D01*
G01X774718D02*
X774948Y373308D01*
X775140Y373567D01*
X775217Y373877D01*
X775140Y374187D01*
X774948Y374445D01*
X774603Y374600D01*
X774258Y374548D01*
X773913Y374342D01*
G01X781417Y371500D02*
X779883D01*
Y374600D01*
X781417D01*
G01X780803Y373102D02*
X779883D01*
G01X782868Y371500D02*
Y374600D01*
X784632Y371500D01*
Y374600D01*
G01X785892Y371500D02*
X786850Y374600D01*
X787808Y371500D01*
G01X787463Y372585D02*
X786237D01*
G01X790257Y373153D02*
X790410Y373308D01*
X790525Y373567D01*
X790602Y373928D01*
X790525Y374238D01*
X790372Y374445D01*
X790103Y374600D01*
X789068D01*
Y371500D01*
X790333D01*
X790602Y371707D01*
X790755Y372017D01*
X790832Y372378D01*
X790755Y372740D01*
X790525Y373050D01*
X790257Y373153D01*
X789068D01*
G01X792283Y374600D02*
Y371500D01*
X793817D01*
G01X796917D02*
X795383D01*
Y374600D01*
X796917D01*
G01X796303Y373102D02*
X795383D01*
G01X805300Y77500D02*
X778347D01*
Y324468D01*
X805500D01*
G01X779233Y338500D02*
Y343500D01*
X780753D01*
X781260Y343250D01*
X781640Y342667D01*
X781767Y342000D01*
X781640Y341333D01*
X781323Y340833D01*
X780753Y340583D01*
X779233D01*
G01X785600Y338500D02*
X785093Y338583D01*
X784650Y338917D01*
X784270Y339417D01*
X784017Y340000D01*
X783890Y340667D01*
Y341333D01*
X784017Y342000D01*
X784270Y342583D01*
X784650Y343083D01*
X785093Y343417D01*
X785600Y343500D01*
X786107Y343417D01*
X786550Y343083D01*
X786930Y342583D01*
X787183Y342000D01*
X787310Y341333D01*
Y340667D01*
X787183Y340000D01*
X786930Y339417D01*
X786550Y338917D01*
X786107Y338583D01*
X785600Y338500D01*
G01X788800Y343500D02*
X789687Y338500D01*
X790700Y343500D01*
X791713Y338500D01*
X792600Y343500D01*
G01X797067Y338500D02*
X794533D01*
Y343500D01*
X797067D01*
G01X796053Y341083D02*
X794533D01*
G01X799633Y338500D02*
Y343500D01*
X801217D01*
X801723Y343250D01*
X802040Y342917D01*
X802167Y342250D01*
X802040Y341583D01*
X801660Y341167D01*
X801217Y340917D01*
X799633D01*
G01X801217D02*
X802167Y338500D01*
G01X812493Y343083D02*
X812113Y343333D01*
X811670Y343500D01*
X811163D01*
X810593Y343250D01*
X810150Y342833D01*
X809833Y342333D01*
X809580Y341500D01*
X809517Y340750D01*
X809643Y340000D01*
X809833Y339500D01*
X810213Y339000D01*
X810657Y338667D01*
X811100Y338500D01*
X811543D01*
X811987Y338667D01*
X812367Y338917D01*
X812683Y339250D01*
G01X816200Y338500D02*
X815693Y338583D01*
X815250Y338917D01*
X814870Y339417D01*
X814617Y340000D01*
X814490Y340667D01*
Y341333D01*
X814617Y342000D01*
X814870Y342583D01*
X815250Y343083D01*
X815693Y343417D01*
X816200Y343500D01*
X816707Y343417D01*
X817150Y343083D01*
X817530Y342583D01*
X817783Y342000D01*
X817910Y341333D01*
Y340667D01*
X817783Y340000D01*
X817530Y339417D01*
X817150Y338917D01*
X816707Y338583D01*
X816200Y338500D01*
G01X819843D02*
Y343500D01*
X822757Y338500D01*
Y343500D01*
G01X824943Y338500D02*
Y343500D01*
X827857Y338500D01*
Y343500D01*
G01X835397Y342667D02*
X835777Y343167D01*
X836220Y343417D01*
X836727Y343500D01*
X837360Y343333D01*
X837803Y342917D01*
X837930Y342417D01*
X837867Y341917D01*
X837613Y341500D01*
X836347Y340667D01*
X835777Y340083D01*
X835397Y339250D01*
X835270Y338500D01*
X837930D01*
G01X821883Y348620D02*
X822075Y348310D01*
X822305Y348103D01*
X822573Y348000D01*
X822880Y348103D01*
X823110Y348310D01*
X823340Y348620D01*
X823417Y349033D01*
Y351100D01*
G01X824983Y348000D02*
Y351100D01*
X825903D01*
X826210Y350945D01*
X826440Y350583D01*
X826517Y350170D01*
X826440Y349757D01*
X826248Y349447D01*
X825903Y349292D01*
X824983D01*
G01X828122D02*
X828390Y349653D01*
X828620Y349860D01*
X828927Y349963D01*
X829195Y349860D01*
X829387Y349653D01*
X829540Y349343D01*
X829578Y348982D01*
X829540Y348672D01*
X829387Y348362D01*
X829157Y348103D01*
X828888Y348000D01*
X828582Y348103D01*
X828313Y348413D01*
X828160Y348878D01*
X828122Y349395D01*
X828198Y350067D01*
X828313Y350428D01*
X828505Y350790D01*
X828773Y351048D01*
X829042Y351100D01*
X829310Y350997D01*
X829502Y350738D01*
G01X830762Y356944D02*
X821038D01*
Y387456D01*
X830762D01*
Y356944D01*
G01X826713Y388357D02*
X827075Y388587D01*
X827281Y388893D01*
X827333Y389238D01*
X827281Y389545D01*
X827023Y389852D01*
X826713Y390043D01*
X826403Y390082D01*
X826041Y390005D01*
X825783Y389737D01*
X825680Y389468D01*
Y389123D01*
G01Y389468D02*
X825525Y389698D01*
X825266Y389890D01*
X824956Y389967D01*
X824646Y389890D01*
X824388Y389698D01*
X824233Y389353D01*
X824285Y389008D01*
X824491Y388663D01*
G01X835748Y303800D02*
Y98600D01*
G01X840345Y394000D02*
Y397100D01*
G01X841955D02*
Y394000D01*
G01Y395550D02*
X840345D01*
G01X843445Y394413D02*
X843752Y394155D01*
X844097Y394000D01*
X844403D01*
X844710Y394155D01*
X844940Y394413D01*
X845055Y394775D01*
X844978Y395137D01*
X844787Y395447D01*
X844442Y395653D01*
X843982Y395757D01*
X843713Y395963D01*
X843598Y396325D01*
X843675Y396687D01*
X843867Y396945D01*
X844135Y397100D01*
X844403D01*
X844672Y396997D01*
X844902Y396738D01*
G01X848193Y396842D02*
X847963Y396997D01*
X847695Y397100D01*
X847388D01*
X847043Y396945D01*
X846775Y396687D01*
X846583Y396377D01*
X846430Y395860D01*
X846392Y395395D01*
X846468Y394930D01*
X846583Y394620D01*
X846813Y394310D01*
X847082Y394103D01*
X847350Y394000D01*
X847618D01*
X847887Y394103D01*
X848117Y394258D01*
X848308Y394465D01*
G01X852707Y394000D02*
Y397100D01*
X853473D01*
X853780Y396945D01*
X854010Y396738D01*
X854202Y396428D01*
X854355Y396067D01*
X854393Y395550D01*
X854355Y395033D01*
X854202Y394672D01*
X854010Y394362D01*
X853780Y394155D01*
X853473Y394000D01*
X852707D01*
G01X857417D02*
X855883D01*
Y397100D01*
X857417D01*
G01X856803Y395602D02*
X855883D01*
G01X860057Y395653D02*
X860210Y395808D01*
X860325Y396067D01*
X860402Y396428D01*
X860325Y396738D01*
X860172Y396945D01*
X859903Y397100D01*
X858868D01*
Y394000D01*
X860133D01*
X860402Y394207D01*
X860555Y394517D01*
X860632Y394878D01*
X860555Y395240D01*
X860325Y395550D01*
X860057Y395653D01*
X858868D01*
G01X862007Y397100D02*
Y394878D01*
X862160Y394413D01*
X862467Y394103D01*
X862850Y394000D01*
X863233Y394103D01*
X863540Y394413D01*
X863693Y394878D01*
Y397100D01*
G01X866180Y395550D02*
X866947D01*
Y394620D01*
X866717Y394310D01*
X866448Y394103D01*
X866065Y394000D01*
X865682Y394103D01*
X865413Y394310D01*
X865183Y394620D01*
X865030Y394982D01*
X864953Y395395D01*
Y395757D01*
X865030Y396067D01*
X865183Y396428D01*
X865413Y396738D01*
X865643Y396945D01*
X865950Y397100D01*
X866218D01*
X866525Y396997D01*
X866755Y396790D01*
G01X871345Y394000D02*
Y397100D01*
G01X872955D02*
Y394000D01*
G01Y395550D02*
X871345D01*
G01X876017Y394000D02*
X874483D01*
Y397100D01*
X876017D01*
G01X875403Y395602D02*
X874483D01*
G01X877392Y394000D02*
X878350Y397100D01*
X879308Y394000D01*
G01X878963Y395085D02*
X877737D01*
G01X880607Y394000D02*
Y397100D01*
X881373D01*
X881680Y396945D01*
X881910Y396738D01*
X882102Y396428D01*
X882255Y396067D01*
X882293Y395550D01*
X882255Y395033D01*
X882102Y394672D01*
X881910Y394362D01*
X881680Y394155D01*
X881373Y394000D01*
X880607D01*
G01X885317D02*
X883783D01*
Y397100D01*
X885317D01*
G01X884703Y395602D02*
X883783D01*
G01X886883Y394000D02*
Y397100D01*
X887842D01*
X888148Y396945D01*
X888340Y396738D01*
X888417Y396325D01*
X888340Y395912D01*
X888110Y395653D01*
X887842Y395498D01*
X886883D01*
G01X887842D02*
X888417Y394000D01*
G01X965669Y65689D02*
X884646D01*
Y336279D01*
X965669D01*
Y65689D01*
G01X893847Y169067D02*
X886347D01*
Y171307D01*
X886722Y172054D01*
X887597Y172614D01*
X888597Y172801D01*
X889597Y172614D01*
X890347Y172147D01*
X890722Y171307D01*
Y169067D01*
G01X893847Y176567D02*
X886347D01*
Y178901D01*
X886722Y179647D01*
X887222Y180114D01*
X888222Y180301D01*
X889222Y180114D01*
X889847Y179554D01*
X890222Y178901D01*
Y176567D01*
G01Y178901D02*
X893847Y180301D01*
G01Y187801D02*
Y184067D01*
X886347D01*
Y187801D01*
G01X889972Y186307D02*
Y184067D01*
G01X892847Y191474D02*
X893472Y192221D01*
X893847Y193061D01*
Y193807D01*
X893472Y194554D01*
X892847Y195114D01*
X891972Y195394D01*
X891097Y195207D01*
X890347Y194741D01*
X889847Y193901D01*
X889597Y192781D01*
X889097Y192127D01*
X888222Y191847D01*
X887347Y192034D01*
X886722Y192501D01*
X886347Y193154D01*
Y193807D01*
X886597Y194461D01*
X887222Y195021D01*
G01X892847Y198974D02*
X893472Y199721D01*
X893847Y200561D01*
Y201307D01*
X893472Y202054D01*
X892847Y202614D01*
X891972Y202894D01*
X891097Y202707D01*
X890347Y202241D01*
X889847Y201401D01*
X889597Y200281D01*
X889097Y199627D01*
X888222Y199347D01*
X887347Y199534D01*
X886722Y200001D01*
X886347Y200654D01*
Y201307D01*
X886597Y201961D01*
X887222Y202521D01*
G01X891347Y207221D02*
Y209647D01*
G01X893847Y214161D02*
X886347D01*
Y217707D01*
G01X889972Y216401D02*
Y214161D01*
G01X886347Y222314D02*
Y224554D01*
G01Y223434D02*
X893847D01*
G01Y222314D02*
Y224554D01*
G01X886347Y230934D02*
X893847D01*
G01X886347Y228787D02*
Y233081D01*
G01X865257Y352070D02*
X865487Y351708D01*
X865793Y351502D01*
X866138Y351450D01*
X866445Y351502D01*
X866752Y351760D01*
X866943Y352070D01*
X866982Y352380D01*
X866905Y352742D01*
X866637Y353000D01*
X866368Y353103D01*
X866023D01*
G01X866368D02*
X866598Y353258D01*
X866790Y353517D01*
X866867Y353827D01*
X866790Y354137D01*
X866598Y354395D01*
X866253Y354550D01*
X865908Y354498D01*
X865563Y354292D01*
G01X861538Y387456D02*
X871262D01*
Y356944D01*
X861538D01*
Y387456D01*
G01X870883Y389120D02*
X871075Y388810D01*
X871305Y388603D01*
X871573Y388500D01*
X871880Y388603D01*
X872110Y388810D01*
X872340Y389120D01*
X872417Y389533D01*
Y391600D01*
G01X873983Y388500D02*
Y391600D01*
X874903D01*
X875210Y391445D01*
X875440Y391083D01*
X875517Y390670D01*
X875440Y390257D01*
X875248Y389947D01*
X874903Y389792D01*
X873983D01*
G01X877007Y389120D02*
X877237Y388758D01*
X877543Y388552D01*
X877888Y388500D01*
X878195Y388552D01*
X878502Y388810D01*
X878693Y389120D01*
X878732Y389430D01*
X878655Y389792D01*
X878387Y390050D01*
X878118Y390153D01*
X877773D01*
G01X878118D02*
X878348Y390308D01*
X878540Y390567D01*
X878617Y390877D01*
X878540Y391187D01*
X878348Y391445D01*
X878003Y391600D01*
X877658Y391548D01*
X877313Y391342D01*
G01X879700Y360400D02*
X873500D01*
Y363600D01*
X879700D01*
Y360400D01*
G01Y380400D02*
X873500D01*
Y383600D01*
X879700D01*
Y380400D01*
G01X923300Y77500D02*
X896457D01*
Y324468D01*
X923500D01*
G01X896233Y338500D02*
Y343500D01*
X897753D01*
X898260Y343250D01*
X898640Y342667D01*
X898767Y342000D01*
X898640Y341333D01*
X898323Y340833D01*
X897753Y340583D01*
X896233D01*
G01X902600Y338500D02*
X902093Y338583D01*
X901650Y338917D01*
X901270Y339417D01*
X901017Y340000D01*
X900890Y340667D01*
Y341333D01*
X901017Y342000D01*
X901270Y342583D01*
X901650Y343083D01*
X902093Y343417D01*
X902600Y343500D01*
X903107Y343417D01*
X903550Y343083D01*
X903930Y342583D01*
X904183Y342000D01*
X904310Y341333D01*
Y340667D01*
X904183Y340000D01*
X903930Y339417D01*
X903550Y338917D01*
X903107Y338583D01*
X902600Y338500D01*
G01X905800Y343500D02*
X906687Y338500D01*
X907700Y343500D01*
X908713Y338500D01*
X909600Y343500D01*
G01X914067Y338500D02*
X911533D01*
Y343500D01*
X914067D01*
G01X913053Y341083D02*
X911533D01*
G01X916633Y338500D02*
Y343500D01*
X918217D01*
X918723Y343250D01*
X919040Y342917D01*
X919167Y342250D01*
X919040Y341583D01*
X918660Y341167D01*
X918217Y340917D01*
X916633D01*
G01X918217D02*
X919167Y338500D01*
G01X929493Y343083D02*
X929113Y343333D01*
X928670Y343500D01*
X928163D01*
X927593Y343250D01*
X927150Y342833D01*
X926833Y342333D01*
X926580Y341500D01*
X926517Y340750D01*
X926643Y340000D01*
X926833Y339500D01*
X927213Y339000D01*
X927657Y338667D01*
X928100Y338500D01*
X928543D01*
X928987Y338667D01*
X929367Y338917D01*
X929683Y339250D01*
G01X933200Y338500D02*
X932693Y338583D01*
X932250Y338917D01*
X931870Y339417D01*
X931617Y340000D01*
X931490Y340667D01*
Y341333D01*
X931617Y342000D01*
X931870Y342583D01*
X932250Y343083D01*
X932693Y343417D01*
X933200Y343500D01*
X933707Y343417D01*
X934150Y343083D01*
X934530Y342583D01*
X934783Y342000D01*
X934910Y341333D01*
Y340667D01*
X934783Y340000D01*
X934530Y339417D01*
X934150Y338917D01*
X933707Y338583D01*
X933200Y338500D01*
G01X936843D02*
Y343500D01*
X939757Y338500D01*
Y343500D01*
G01X941943Y338500D02*
Y343500D01*
X944857Y338500D01*
Y343500D01*
G01X953600Y338500D02*
Y343500D01*
X952840Y342500D01*
G01Y338500D02*
X954360D01*
G01X902883Y348120D02*
X903075Y347810D01*
X903305Y347603D01*
X903573Y347500D01*
X903880Y347603D01*
X904110Y347810D01*
X904340Y348120D01*
X904417Y348533D01*
Y350600D01*
G01X905983Y347500D02*
Y350600D01*
X906903D01*
X907210Y350445D01*
X907440Y350083D01*
X907517Y349670D01*
X907440Y349257D01*
X907248Y348947D01*
X906903Y348792D01*
X905983D01*
G01X909007Y347965D02*
X909237Y347707D01*
X909505Y347552D01*
X909850Y347500D01*
X910195Y347603D01*
X910463Y347810D01*
X910655Y348172D01*
X910693Y348585D01*
X910617Y348998D01*
X910425Y349257D01*
X910157Y349463D01*
X909888Y349515D01*
X909620Y349463D01*
X909275Y349257D01*
X909390Y350600D01*
X910425D01*
G01X911762Y356944D02*
X902038D01*
Y387456D01*
X911762D01*
Y356944D01*
G01X914670Y383500D02*
Y388500D01*
G01X917330D02*
Y383500D01*
G01Y386000D02*
X914670D01*
G01X919770Y384167D02*
X920277Y383750D01*
X920847Y383500D01*
X921353D01*
X921860Y383750D01*
X922240Y384167D01*
X922430Y384750D01*
X922303Y385333D01*
X921987Y385833D01*
X921417Y386167D01*
X920657Y386333D01*
X920213Y386667D01*
X920023Y387250D01*
X920150Y387833D01*
X920467Y388250D01*
X920910Y388500D01*
X921353D01*
X921797Y388333D01*
X922177Y387917D01*
G01X927593Y388083D02*
X927213Y388333D01*
X926770Y388500D01*
X926263D01*
X925693Y388250D01*
X925250Y387833D01*
X924933Y387333D01*
X924680Y386500D01*
X924617Y385750D01*
X924743Y385000D01*
X924933Y384500D01*
X925313Y384000D01*
X925757Y383667D01*
X926200Y383500D01*
X926643D01*
X927087Y383667D01*
X927467Y383917D01*
X927783Y384250D01*
G01X931300Y383500D02*
Y388500D01*
X930540Y387500D01*
G01Y383500D02*
X932060D01*
G01X942767D02*
X940233D01*
Y388500D01*
X942767D01*
G01X941753Y386083D02*
X940233D01*
G01X945143Y383500D02*
Y388500D01*
X948057Y383500D01*
Y388500D01*
G01X950117Y383500D02*
X951700Y388500D01*
X953283Y383500D01*
G01X952713Y385250D02*
X950687D01*
G01X957307Y386167D02*
X957560Y386417D01*
X957750Y386833D01*
X957877Y387417D01*
X957750Y387917D01*
X957497Y388250D01*
X957053Y388500D01*
X955343D01*
Y383500D01*
X957433D01*
X957877Y383833D01*
X958130Y384333D01*
X958257Y384917D01*
X958130Y385500D01*
X957750Y386000D01*
X957307Y386167D01*
X955343D01*
G01X960633Y388500D02*
Y383500D01*
X963167D01*
G01X968267D02*
X965733D01*
Y388500D01*
X968267D01*
G01X967253Y386083D02*
X965733D01*
G01X916475Y376892D02*
Y379992D01*
X916015Y379372D01*
G01Y376892D02*
X916935D01*
G01X919077Y377925D02*
X920073D01*
G01X921947Y379475D02*
X922177Y379785D01*
X922445Y379940D01*
X922752Y379992D01*
X923135Y379889D01*
X923403Y379630D01*
X923480Y379320D01*
X923442Y379010D01*
X923288Y378752D01*
X922522Y378235D01*
X922177Y377874D01*
X921947Y377357D01*
X921870Y376892D01*
X923480D01*
G01X928032D02*
Y379992D01*
X928798D01*
X929105Y379837D01*
X929335Y379630D01*
X929527Y379320D01*
X929680Y378959D01*
X929718Y378442D01*
X929680Y377925D01*
X929527Y377564D01*
X929335Y377254D01*
X929105Y377047D01*
X928798Y376892D01*
X928032D01*
G01X931515Y379992D02*
X932435D01*
G01X931975D02*
Y376892D01*
G01X931515D02*
X932435D01*
G01X934270Y377305D02*
X934577Y377047D01*
X934922Y376892D01*
X935228D01*
X935535Y377047D01*
X935765Y377305D01*
X935880Y377667D01*
X935803Y378029D01*
X935612Y378339D01*
X935267Y378545D01*
X934807Y378649D01*
X934538Y378855D01*
X934423Y379217D01*
X934500Y379579D01*
X934692Y379837D01*
X934960Y379992D01*
X935228D01*
X935497Y379889D01*
X935727Y379630D01*
G01X937217Y376892D02*
X938175Y379992D01*
X939133Y376892D01*
G01X938788Y377977D02*
X937562D01*
G01X941582Y378545D02*
X941735Y378700D01*
X941850Y378959D01*
X941927Y379320D01*
X941850Y379630D01*
X941697Y379837D01*
X941428Y379992D01*
X940393D01*
Y376892D01*
X941658D01*
X941927Y377099D01*
X942080Y377409D01*
X942157Y377770D01*
X942080Y378132D01*
X941850Y378442D01*
X941582Y378545D01*
X940393D01*
G01X943608Y379992D02*
Y376892D01*
X945142D01*
G01X948242D02*
X946708D01*
Y379992D01*
X948242D01*
G01X947628Y378494D02*
X946708D01*
G01X915522Y374583D02*
X915752Y374893D01*
X916020Y375048D01*
X916327Y375100D01*
X916710Y374997D01*
X916978Y374738D01*
X917055Y374428D01*
X917017Y374118D01*
X916863Y373860D01*
X916097Y373343D01*
X915752Y372982D01*
X915522Y372465D01*
X915445Y372000D01*
X917055D01*
G01X918852Y373033D02*
X919848D01*
G01X921607Y372620D02*
X921837Y372258D01*
X922143Y372052D01*
X922488Y372000D01*
X922795Y372052D01*
X923102Y372310D01*
X923293Y372620D01*
X923332Y372930D01*
X923255Y373292D01*
X922987Y373550D01*
X922718Y373653D01*
X922373D01*
G01X922718D02*
X922948Y373808D01*
X923140Y374067D01*
X923217Y374377D01*
X923140Y374687D01*
X922948Y374945D01*
X922603Y375100D01*
X922258Y375048D01*
X921913Y374842D01*
G01X929417Y372000D02*
X927883D01*
Y375100D01*
X929417D01*
G01X928803Y373602D02*
X927883D01*
G01X930868Y372000D02*
Y375100D01*
X932632Y372000D01*
Y375100D01*
G01X933892Y372000D02*
X934850Y375100D01*
X935808Y372000D01*
G01X935463Y373085D02*
X934237D01*
G01X938257Y373653D02*
X938410Y373808D01*
X938525Y374067D01*
X938602Y374428D01*
X938525Y374738D01*
X938372Y374945D01*
X938103Y375100D01*
X937068D01*
Y372000D01*
X938333D01*
X938602Y372207D01*
X938755Y372517D01*
X938832Y372878D01*
X938755Y373240D01*
X938525Y373550D01*
X938257Y373653D01*
X937068D01*
G01X940283Y375100D02*
Y372000D01*
X941817D01*
G01X944917D02*
X943383D01*
Y375100D01*
X944917D01*
G01X944303Y373602D02*
X943383D01*
G01X907713Y388357D02*
X908075Y388587D01*
X908281Y388893D01*
X908333Y389238D01*
X908281Y389545D01*
X908023Y389852D01*
X907713Y390043D01*
X907403Y390082D01*
X907041Y390005D01*
X906783Y389737D01*
X906680Y389468D01*
Y389123D01*
G01Y389468D02*
X906525Y389698D01*
X906266Y389890D01*
X905956Y389967D01*
X905646Y389890D01*
X905388Y389698D01*
X905233Y389353D01*
X905285Y389008D01*
X905491Y388663D01*
G01X982345Y42500D02*
Y45600D01*
G01X983955D02*
Y42500D01*
G01Y44050D02*
X982345D01*
G01X985598Y42862D02*
X985867Y42603D01*
X986173Y42500D01*
X986480Y42603D01*
X986748Y42913D01*
X986940Y43378D01*
X987017Y43843D01*
Y44412D01*
X986940Y44877D01*
X986748Y45290D01*
X986518Y45497D01*
X986250Y45600D01*
X985943Y45497D01*
X985713Y45290D01*
X985560Y44980D01*
X985483Y44567D01*
X985560Y44205D01*
X985752Y43843D01*
X985982Y43637D01*
X986250Y43585D01*
X986557Y43688D01*
X986787Y43947D01*
X987017Y44412D01*
G01X953858Y303000D02*
Y101100D01*
G01X981845Y321500D02*
Y324600D01*
G01X983455D02*
Y321500D01*
G01Y323050D02*
X981845D01*
G01X985750Y321500D02*
X986018Y321552D01*
X986325Y321707D01*
X986517Y321965D01*
X986593Y322327D01*
X986517Y322688D01*
X986287Y322998D01*
X985942Y323153D01*
X985558D01*
X985328Y323257D01*
X985137Y323515D01*
X985060Y323877D01*
X985175Y324238D01*
X985443Y324497D01*
X985750Y324600D01*
X986057Y324497D01*
X986325Y324238D01*
X986440Y323877D01*
X986363Y323515D01*
X986172Y323257D01*
X985942Y323153D01*
X985558D01*
X985213Y322998D01*
X984983Y322688D01*
X984907Y322327D01*
X984983Y321965D01*
X985175Y321707D01*
X985482Y321552D01*
X985750Y321500D01*
G01X988880Y585883D02*
X989190Y586075D01*
X989397Y586305D01*
X989500Y586573D01*
X989397Y586880D01*
X989190Y587110D01*
X988880Y587340D01*
X988467Y587417D01*
X986400D01*
G01X989500Y589750D02*
X986400D01*
X987020Y589290D01*
G01X989500D02*
Y590210D01*
G01X986400Y592850D02*
X986503Y592543D01*
X986762Y592313D01*
X987072Y592160D01*
X987485Y592045D01*
X987950Y592007D01*
X988415Y592045D01*
X988828Y592160D01*
X989138Y592313D01*
X989397Y592543D01*
X989500Y592850D01*
X989397Y593157D01*
X989138Y593387D01*
X988828Y593540D01*
X988415Y593655D01*
X987950Y593693D01*
X987485Y593655D01*
X987072Y593540D01*
X986762Y593387D01*
X986503Y593157D01*
X986400Y592850D01*
G01X992233Y585074D02*
Y611300D01*
X1026809Y598187D01*
X992233Y585074D01*
G01X1021600Y187200D02*
Y193800D01*
X1034600D01*
Y187200D01*
X1021600D01*
G01X1041000Y201307D02*
X1043222D01*
X1043687Y201460D01*
X1043997Y201767D01*
X1044100Y202150D01*
X1043997Y202533D01*
X1043687Y202840D01*
X1043222Y202993D01*
X1041000D01*
G01X1041517Y204522D02*
X1041207Y204752D01*
X1041052Y205020D01*
X1041000Y205327D01*
X1041103Y205710D01*
X1041362Y205978D01*
X1041672Y206055D01*
X1041982Y206017D01*
X1042240Y205863D01*
X1042757Y205097D01*
X1043118Y204752D01*
X1043635Y204522D01*
X1044100Y204445D01*
Y206055D01*
G01X1041517Y207622D02*
X1041207Y207852D01*
X1041052Y208120D01*
X1041000Y208427D01*
X1041103Y208810D01*
X1041362Y209078D01*
X1041672Y209155D01*
X1041982Y209117D01*
X1042240Y208963D01*
X1042757Y208197D01*
X1043118Y207852D01*
X1043635Y207622D01*
X1044100Y207545D01*
Y209155D01*
G01X1053006Y187188D02*
X1041194D01*
Y199812D01*
X1053006D01*
Y187188D01*
G01X1017207Y199100D02*
Y196878D01*
X1017360Y196413D01*
X1017667Y196103D01*
X1018050Y196000D01*
X1018433Y196103D01*
X1018740Y196413D01*
X1018893Y196878D01*
Y199100D01*
G01X1020422Y198583D02*
X1020652Y198893D01*
X1020920Y199048D01*
X1021227Y199100D01*
X1021610Y198997D01*
X1021878Y198738D01*
X1021955Y198428D01*
X1021917Y198118D01*
X1021763Y197860D01*
X1020997Y197343D01*
X1020652Y196982D01*
X1020422Y196465D01*
X1020345Y196000D01*
X1021955D01*
G01X1024710D02*
Y199100D01*
X1023292Y196878D01*
X1025208D01*
G01X1026688Y195594D02*
Y207406D01*
X1039312D01*
Y195594D01*
X1026688D01*
G01X1036000Y187400D02*
Y193600D01*
X1039200D01*
Y187400D01*
X1036000D01*
G01X1071200Y305900D02*
X1065000D01*
Y309100D01*
X1071200D01*
Y305900D01*
G01Y309900D02*
X1065000D01*
Y313100D01*
X1071200D01*
Y309900D01*
G01X1081000Y257100D02*
X1087200D01*
Y253900D01*
X1081000D01*
Y257100D01*
G01X1087200Y249900D02*
X1081000D01*
Y253100D01*
X1087200D01*
Y249900D01*
G01X1094000Y297600D02*
X1100200D01*
Y294400D01*
X1094000D01*
Y297600D01*
G01X1100200Y289900D02*
X1094000D01*
Y293100D01*
X1100200D01*
Y289900D01*
G01Y285900D02*
X1094000D01*
Y289100D01*
X1100200D01*
Y285900D01*
G01X1094000Y302100D02*
X1100200D01*
Y298900D01*
X1094000D01*
Y302100D01*
G01X1112400Y302800D02*
X1122600D01*
Y298200D01*
X1112400D01*
Y302800D01*
G01X1103500Y302100D02*
X1109700D01*
Y298900D01*
X1103500D01*
Y302100D01*
G01X1109700Y294400D02*
X1103500D01*
Y297600D01*
X1109700D01*
Y294400D01*
G01X1103500Y293100D02*
X1109700D01*
Y289900D01*
X1103500D01*
Y293100D01*
G01Y286600D02*
X1109700D01*
Y283400D01*
X1103500D01*
Y286600D01*
G01X1113500Y297600D02*
X1119700D01*
Y294400D01*
X1113500D01*
Y297600D01*
G01X1151100Y249900D02*
X1144900D01*
Y253100D01*
X1151100D01*
Y249900D01*
G01X1183133Y96450D02*
Y99550D01*
X1184053D01*
X1184360Y99395D01*
X1184590Y99033D01*
X1184667Y98620D01*
X1184590Y98207D01*
X1184398Y97897D01*
X1184053Y97742D01*
X1183133D01*
G01X1186233Y96450D02*
Y99550D01*
X1187192D01*
X1187498Y99395D01*
X1187690Y99188D01*
X1187767Y98775D01*
X1187690Y98362D01*
X1187460Y98103D01*
X1187192Y97948D01*
X1186233D01*
G01X1187192D02*
X1187767Y96450D01*
G01X1189257Y97070D02*
X1189487Y96708D01*
X1189793Y96502D01*
X1190138Y96450D01*
X1190445Y96502D01*
X1190752Y96760D01*
X1190943Y97070D01*
X1190982Y97380D01*
X1190905Y97742D01*
X1190637Y98000D01*
X1190368Y98103D01*
X1190023D01*
G01X1190368D02*
X1190598Y98258D01*
X1190790Y98517D01*
X1190867Y98827D01*
X1190790Y99137D01*
X1190598Y99395D01*
X1190253Y99550D01*
X1189908Y99498D01*
X1189563Y99292D01*
G01X1193200Y96450D02*
Y99550D01*
X1192740Y98930D01*
G01Y96450D02*
X1193660D01*
G01X1195457Y96915D02*
X1195687Y96657D01*
X1195955Y96502D01*
X1196300Y96450D01*
X1196645Y96553D01*
X1196913Y96760D01*
X1197105Y97122D01*
X1197143Y97535D01*
X1197067Y97948D01*
X1196875Y98207D01*
X1196607Y98413D01*
X1196338Y98465D01*
X1196070Y98413D01*
X1195725Y98207D01*
X1195840Y99550D01*
X1196875D01*
G01X1183577Y102200D02*
Y130400D01*
X1214977D01*
Y102200D01*
X1183577D01*
G01X1195700Y147000D02*
X1185500D01*
Y151600D01*
X1195700D01*
Y147000D01*
G01Y133000D02*
X1185500D01*
Y137600D01*
X1195700D01*
Y133000D01*
G01X1185500Y144600D02*
X1195700D01*
Y140000D01*
X1185500D01*
Y144600D01*
G01X1184133Y229450D02*
Y232550D01*
X1185053D01*
X1185360Y232395D01*
X1185590Y232033D01*
X1185667Y231620D01*
X1185590Y231207D01*
X1185398Y230897D01*
X1185053Y230742D01*
X1184133D01*
G01X1187233Y229450D02*
Y232550D01*
X1188192D01*
X1188498Y232395D01*
X1188690Y232188D01*
X1188767Y231775D01*
X1188690Y231362D01*
X1188460Y231103D01*
X1188192Y230948D01*
X1187233D01*
G01X1188192D02*
X1188767Y229450D01*
G01X1191560D02*
Y232550D01*
X1190142Y230328D01*
X1192058D01*
G01X1194123Y229450D02*
X1194200Y230122D01*
X1194315Y230690D01*
X1194468Y231207D01*
X1194660Y231775D01*
X1194967Y232550D01*
X1193433D01*
G01X1196648Y229812D02*
X1196917Y229553D01*
X1197223Y229450D01*
X1197530Y229553D01*
X1197798Y229863D01*
X1197990Y230328D01*
X1198067Y230793D01*
Y231362D01*
X1197990Y231827D01*
X1197798Y232240D01*
X1197568Y232447D01*
X1197300Y232550D01*
X1196993Y232447D01*
X1196763Y232240D01*
X1196610Y231930D01*
X1196533Y231517D01*
X1196610Y231155D01*
X1196802Y230793D01*
X1197032Y230587D01*
X1197300Y230535D01*
X1197607Y230638D01*
X1197837Y230897D01*
X1198067Y231362D01*
G01X1183577Y235400D02*
Y263600D01*
X1214977D01*
Y235400D01*
X1183577D01*
G01X1195700Y266200D02*
X1185500D01*
Y270800D01*
X1195700D01*
Y266200D01*
G01Y280200D02*
X1185500D01*
Y284800D01*
X1195700D01*
Y280200D01*
G01Y273200D02*
X1185500D01*
Y277800D01*
X1195700D01*
Y273200D01*
G01X1202500Y151600D02*
X1212700D01*
Y147000D01*
X1202500D01*
Y151600D01*
G01Y137600D02*
X1212700D01*
Y133000D01*
X1202500D01*
Y137600D01*
G01X1212700Y140000D02*
X1202500D01*
Y144600D01*
X1212700D01*
Y140000D01*
G01X1195900Y156900D02*
X1202100D01*
Y153700D01*
X1195900D01*
Y156900D01*
G01X1202500Y270800D02*
X1212700D01*
Y266200D01*
X1202500D01*
Y270800D01*
G01X1221928Y300181D02*
G03I-9450J0D01*
G01X1195900Y290100D02*
X1202100D01*
Y286900D01*
X1195900D01*
Y290100D01*
G01X1202500Y284800D02*
X1212700D01*
Y280200D01*
X1202500D01*
Y284800D01*
G01Y277800D02*
X1212700D01*
Y273200D01*
X1202500D01*
Y277800D01*
G01X1208223Y312681D02*
Y315781D01*
G01X1209833D02*
Y312681D01*
G01Y314231D02*
X1208223D01*
G01X1211400Y315264D02*
X1211630Y315574D01*
X1211898Y315729D01*
X1212205Y315781D01*
X1212588Y315678D01*
X1212856Y315419D01*
X1212933Y315109D01*
X1212895Y314799D01*
X1212741Y314541D01*
X1211975Y314024D01*
X1211630Y313663D01*
X1211400Y313146D01*
X1211323Y312681D01*
X1212933D01*
G01X1214500Y313973D02*
X1214768Y314334D01*
X1214998Y314541D01*
X1215305Y314644D01*
X1215573Y314541D01*
X1215765Y314334D01*
X1215918Y314024D01*
X1215956Y313663D01*
X1215918Y313353D01*
X1215765Y313043D01*
X1215535Y312784D01*
X1215266Y312681D01*
X1214960Y312784D01*
X1214691Y313094D01*
X1214538Y313559D01*
X1214500Y314076D01*
X1214576Y314748D01*
X1214691Y315109D01*
X1214883Y315471D01*
X1215151Y315729D01*
X1215420Y315781D01*
X1215688Y315678D01*
X1215880Y315419D01*
G01X1252049Y52215D02*
X1302308D01*
Y58800D01*
G01X1242072Y91585D02*
Y52215D01*
X1242149D01*
G01X1302308Y85000D02*
Y91585D01*
X1252049D01*
G01X1242149D02*
X1242072D01*
G01X1252049Y96615D02*
X1302308D01*
Y103200D01*
G01X1242072Y135985D02*
Y96615D01*
X1242149D01*
G01X1302308Y129400D02*
Y135985D01*
X1252049D01*
G01X1242149D02*
X1242072D01*
G01X1252049Y141015D02*
X1302308D01*
Y147600D01*
G01X1242072Y180385D02*
Y141015D01*
X1242149D01*
G01X1252049Y185415D02*
X1302308D01*
Y192000D01*
G01X1242072Y224785D02*
Y185415D01*
X1242149D01*
G01X1302308Y173800D02*
Y180385D01*
X1252049D01*
G01X1242149D02*
X1242072D01*
G01X1302308Y218200D02*
Y224785D01*
X1252049D01*
G01X1242149D02*
X1242072D01*
G01X1252049Y229815D02*
X1302308D01*
Y236400D01*
G01X1242072Y269185D02*
Y229815D01*
X1242149D01*
G01X1302308Y262600D02*
Y269185D01*
X1252049D01*
G01X1242149D02*
X1242072D01*
G01X1252049Y274215D02*
X1302308D01*
Y280800D01*
G01X1242072Y313585D02*
Y274215D01*
X1242149D01*
G01X1302308Y307000D02*
Y313585D01*
X1252049D01*
G01X1242149D02*
X1242072D01*
G01X1251950Y328400D02*
X1245750D01*
Y331600D01*
X1251950D01*
Y328400D01*
G01X1255100D02*
X1248900D01*
Y331600D01*
X1255100D01*
Y328400D01*
G01Y335400D02*
X1248900D01*
Y338600D01*
X1255100D01*
Y335400D01*
G01X1245750Y338600D02*
X1251950D01*
Y335400D01*
X1245750D01*
Y338600D01*
G01X1275000Y340000D02*
Y327000D01*
X1260000D01*
Y340000D01*
X1275000D01*
G01X1266083Y340950D02*
Y344050D01*
X1267003D01*
X1267310Y343895D01*
X1267540Y343533D01*
X1267617Y343120D01*
X1267540Y342707D01*
X1267348Y342397D01*
X1267003Y342242D01*
X1266083D01*
G01X1269950Y340950D02*
X1269643Y341002D01*
X1269375Y341208D01*
X1269145Y341518D01*
X1268992Y341880D01*
X1268915Y342293D01*
Y342707D01*
X1268992Y343120D01*
X1269145Y343482D01*
X1269375Y343792D01*
X1269643Y343998D01*
X1269950Y344050D01*
X1270257Y343998D01*
X1270525Y343792D01*
X1270755Y343482D01*
X1270908Y343120D01*
X1270985Y342707D01*
Y342293D01*
X1270908Y341880D01*
X1270755Y341518D01*
X1270525Y341208D01*
X1270257Y341002D01*
X1269950Y340950D01*
G01X1270257Y341777D02*
X1270717Y340950D01*
G01X1272207Y341570D02*
X1272437Y341208D01*
X1272743Y341002D01*
X1273088Y340950D01*
X1273395Y341002D01*
X1273702Y341260D01*
X1273893Y341570D01*
X1273932Y341880D01*
X1273855Y342242D01*
X1273587Y342500D01*
X1273318Y342603D01*
X1272973D01*
G01X1273318D02*
X1273548Y342758D01*
X1273740Y343017D01*
X1273817Y343327D01*
X1273740Y343637D01*
X1273548Y343895D01*
X1273203Y344050D01*
X1272858Y343998D01*
X1272513Y343792D01*
G01X1276073Y340950D02*
X1276150Y341622D01*
X1276265Y342190D01*
X1276418Y342707D01*
X1276610Y343275D01*
X1276917Y344050D01*
X1275383D01*
G01X1310482Y55083D02*
Y58183D01*
X1311402D01*
X1311709Y58028D01*
X1311939Y57666D01*
X1312016Y57253D01*
X1311939Y56840D01*
X1311747Y56530D01*
X1311402Y56375D01*
X1310482D01*
G01X1314349Y55083D02*
X1314042Y55135D01*
X1313774Y55341D01*
X1313544Y55651D01*
X1313391Y56013D01*
X1313314Y56426D01*
Y56840D01*
X1313391Y57253D01*
X1313544Y57615D01*
X1313774Y57925D01*
X1314042Y58131D01*
X1314349Y58183D01*
X1314656Y58131D01*
X1314924Y57925D01*
X1315154Y57615D01*
X1315307Y57253D01*
X1315384Y56840D01*
Y56426D01*
X1315307Y56013D01*
X1315154Y55651D01*
X1314924Y55341D01*
X1314656Y55135D01*
X1314349Y55083D01*
G01X1314656Y55910D02*
X1315116Y55083D01*
G01X1316606Y55703D02*
X1316836Y55341D01*
X1317142Y55135D01*
X1317487Y55083D01*
X1317794Y55135D01*
X1318101Y55393D01*
X1318292Y55703D01*
X1318331Y56013D01*
X1318254Y56375D01*
X1317986Y56633D01*
X1317717Y56736D01*
X1317372D01*
G01X1317717D02*
X1317947Y56891D01*
X1318139Y57150D01*
X1318216Y57460D01*
X1318139Y57770D01*
X1317947Y58028D01*
X1317602Y58183D01*
X1317257Y58131D01*
X1316912Y57925D01*
G01X1319821Y56375D02*
X1320089Y56736D01*
X1320319Y56943D01*
X1320626Y57046D01*
X1320894Y56943D01*
X1321086Y56736D01*
X1321239Y56426D01*
X1321277Y56065D01*
X1321239Y55755D01*
X1321086Y55445D01*
X1320856Y55186D01*
X1320587Y55083D01*
X1320281Y55186D01*
X1320012Y55496D01*
X1319859Y55961D01*
X1319821Y56478D01*
X1319897Y57150D01*
X1320012Y57511D01*
X1320204Y57873D01*
X1320472Y58131D01*
X1320741Y58183D01*
X1321009Y58080D01*
X1321201Y57821D01*
G01X1302308Y65000D02*
Y78800D01*
G01X1310482Y99483D02*
Y102583D01*
X1311402D01*
X1311709Y102428D01*
X1311939Y102066D01*
X1312016Y101653D01*
X1311939Y101240D01*
X1311747Y100930D01*
X1311402Y100775D01*
X1310482D01*
G01X1314349Y99483D02*
X1314042Y99535D01*
X1313774Y99741D01*
X1313544Y100051D01*
X1313391Y100413D01*
X1313314Y100826D01*
Y101240D01*
X1313391Y101653D01*
X1313544Y102015D01*
X1313774Y102325D01*
X1314042Y102531D01*
X1314349Y102583D01*
X1314656Y102531D01*
X1314924Y102325D01*
X1315154Y102015D01*
X1315307Y101653D01*
X1315384Y101240D01*
Y100826D01*
X1315307Y100413D01*
X1315154Y100051D01*
X1314924Y99741D01*
X1314656Y99535D01*
X1314349Y99483D01*
G01X1314656Y100310D02*
X1315116Y99483D01*
G01X1316606Y100103D02*
X1316836Y99741D01*
X1317142Y99535D01*
X1317487Y99483D01*
X1317794Y99535D01*
X1318101Y99793D01*
X1318292Y100103D01*
X1318331Y100413D01*
X1318254Y100775D01*
X1317986Y101033D01*
X1317717Y101136D01*
X1317372D01*
G01X1317717D02*
X1317947Y101291D01*
X1318139Y101550D01*
X1318216Y101860D01*
X1318139Y102170D01*
X1317947Y102428D01*
X1317602Y102583D01*
X1317257Y102531D01*
X1316912Y102325D01*
G01X1319706Y99948D02*
X1319936Y99690D01*
X1320204Y99535D01*
X1320549Y99483D01*
X1320894Y99586D01*
X1321162Y99793D01*
X1321354Y100155D01*
X1321392Y100568D01*
X1321316Y100981D01*
X1321124Y101240D01*
X1320856Y101446D01*
X1320587Y101498D01*
X1320319Y101446D01*
X1319974Y101240D01*
X1320089Y102583D01*
X1321124D01*
G01X1302308Y109400D02*
Y123200D01*
G01X1310482Y143883D02*
Y146983D01*
X1311402D01*
X1311709Y146828D01*
X1311939Y146466D01*
X1312016Y146053D01*
X1311939Y145640D01*
X1311747Y145330D01*
X1311402Y145175D01*
X1310482D01*
G01X1314349Y143883D02*
X1314042Y143935D01*
X1313774Y144141D01*
X1313544Y144451D01*
X1313391Y144813D01*
X1313314Y145226D01*
Y145640D01*
X1313391Y146053D01*
X1313544Y146415D01*
X1313774Y146725D01*
X1314042Y146931D01*
X1314349Y146983D01*
X1314656Y146931D01*
X1314924Y146725D01*
X1315154Y146415D01*
X1315307Y146053D01*
X1315384Y145640D01*
Y145226D01*
X1315307Y144813D01*
X1315154Y144451D01*
X1314924Y144141D01*
X1314656Y143935D01*
X1314349Y143883D01*
G01X1314656Y144710D02*
X1315116Y143883D01*
G01X1316721Y145175D02*
X1316989Y145536D01*
X1317219Y145743D01*
X1317526Y145846D01*
X1317794Y145743D01*
X1317986Y145536D01*
X1318139Y145226D01*
X1318177Y144865D01*
X1318139Y144555D01*
X1317986Y144245D01*
X1317756Y143986D01*
X1317487Y143883D01*
X1317181Y143986D01*
X1316912Y144296D01*
X1316759Y144761D01*
X1316721Y145278D01*
X1316797Y145950D01*
X1316912Y146311D01*
X1317104Y146673D01*
X1317372Y146931D01*
X1317641Y146983D01*
X1317909Y146880D01*
X1318101Y146621D01*
G01X1302308Y153800D02*
Y167600D01*
G01X1310482Y188283D02*
Y191383D01*
X1311402D01*
X1311709Y191228D01*
X1311939Y190866D01*
X1312016Y190453D01*
X1311939Y190040D01*
X1311747Y189730D01*
X1311402Y189575D01*
X1310482D01*
G01X1314349Y188283D02*
X1314042Y188335D01*
X1313774Y188541D01*
X1313544Y188851D01*
X1313391Y189213D01*
X1313314Y189626D01*
Y190040D01*
X1313391Y190453D01*
X1313544Y190815D01*
X1313774Y191125D01*
X1314042Y191331D01*
X1314349Y191383D01*
X1314656Y191331D01*
X1314924Y191125D01*
X1315154Y190815D01*
X1315307Y190453D01*
X1315384Y190040D01*
Y189626D01*
X1315307Y189213D01*
X1315154Y188851D01*
X1314924Y188541D01*
X1314656Y188335D01*
X1314349Y188283D01*
G01X1314656Y189110D02*
X1315116Y188283D01*
G01X1316606Y188903D02*
X1316836Y188541D01*
X1317142Y188335D01*
X1317487Y188283D01*
X1317794Y188335D01*
X1318101Y188593D01*
X1318292Y188903D01*
X1318331Y189213D01*
X1318254Y189575D01*
X1317986Y189833D01*
X1317717Y189936D01*
X1317372D01*
G01X1317717D02*
X1317947Y190091D01*
X1318139Y190350D01*
X1318216Y190660D01*
X1318139Y190970D01*
X1317947Y191228D01*
X1317602Y191383D01*
X1317257Y191331D01*
X1316912Y191125D01*
G01X1321009Y188283D02*
Y191383D01*
X1319591Y189161D01*
X1321507D01*
G01X1302308Y198200D02*
Y212000D01*
G01X1310482Y232683D02*
Y235783D01*
X1311402D01*
X1311709Y235628D01*
X1311939Y235266D01*
X1312016Y234853D01*
X1311939Y234440D01*
X1311747Y234130D01*
X1311402Y233975D01*
X1310482D01*
G01X1314349Y232683D02*
X1314042Y232735D01*
X1313774Y232941D01*
X1313544Y233251D01*
X1313391Y233613D01*
X1313314Y234026D01*
Y234440D01*
X1313391Y234853D01*
X1313544Y235215D01*
X1313774Y235525D01*
X1314042Y235731D01*
X1314349Y235783D01*
X1314656Y235731D01*
X1314924Y235525D01*
X1315154Y235215D01*
X1315307Y234853D01*
X1315384Y234440D01*
Y234026D01*
X1315307Y233613D01*
X1315154Y233251D01*
X1314924Y232941D01*
X1314656Y232735D01*
X1314349Y232683D01*
G01X1314656Y233510D02*
X1315116Y232683D01*
G01X1316606Y233303D02*
X1316836Y232941D01*
X1317142Y232735D01*
X1317487Y232683D01*
X1317794Y232735D01*
X1318101Y232993D01*
X1318292Y233303D01*
X1318331Y233613D01*
X1318254Y233975D01*
X1317986Y234233D01*
X1317717Y234336D01*
X1317372D01*
G01X1317717D02*
X1317947Y234491D01*
X1318139Y234750D01*
X1318216Y235060D01*
X1318139Y235370D01*
X1317947Y235628D01*
X1317602Y235783D01*
X1317257Y235731D01*
X1316912Y235525D01*
G01X1319706Y233303D02*
X1319936Y232941D01*
X1320242Y232735D01*
X1320587Y232683D01*
X1320894Y232735D01*
X1321201Y232993D01*
X1321392Y233303D01*
X1321431Y233613D01*
X1321354Y233975D01*
X1321086Y234233D01*
X1320817Y234336D01*
X1320472D01*
G01X1320817D02*
X1321047Y234491D01*
X1321239Y234750D01*
X1321316Y235060D01*
X1321239Y235370D01*
X1321047Y235628D01*
X1320702Y235783D01*
X1320357Y235731D01*
X1320012Y235525D01*
G01X1302308Y242600D02*
Y256400D01*
G01X1310482Y277083D02*
Y280183D01*
X1311402D01*
X1311709Y280028D01*
X1311939Y279666D01*
X1312016Y279253D01*
X1311939Y278840D01*
X1311747Y278530D01*
X1311402Y278375D01*
X1310482D01*
G01X1314349Y277083D02*
X1314042Y277135D01*
X1313774Y277341D01*
X1313544Y277651D01*
X1313391Y278013D01*
X1313314Y278426D01*
Y278840D01*
X1313391Y279253D01*
X1313544Y279615D01*
X1313774Y279925D01*
X1314042Y280131D01*
X1314349Y280183D01*
X1314656Y280131D01*
X1314924Y279925D01*
X1315154Y279615D01*
X1315307Y279253D01*
X1315384Y278840D01*
Y278426D01*
X1315307Y278013D01*
X1315154Y277651D01*
X1314924Y277341D01*
X1314656Y277135D01*
X1314349Y277083D01*
G01X1314656Y277910D02*
X1315116Y277083D01*
G01X1316606Y277703D02*
X1316836Y277341D01*
X1317142Y277135D01*
X1317487Y277083D01*
X1317794Y277135D01*
X1318101Y277393D01*
X1318292Y277703D01*
X1318331Y278013D01*
X1318254Y278375D01*
X1317986Y278633D01*
X1317717Y278736D01*
X1317372D01*
G01X1317717D02*
X1317947Y278891D01*
X1318139Y279150D01*
X1318216Y279460D01*
X1318139Y279770D01*
X1317947Y280028D01*
X1317602Y280183D01*
X1317257Y280131D01*
X1316912Y279925D01*
G01X1319821Y279666D02*
X1320051Y279976D01*
X1320319Y280131D01*
X1320626Y280183D01*
X1321009Y280080D01*
X1321277Y279821D01*
X1321354Y279511D01*
X1321316Y279201D01*
X1321162Y278943D01*
X1320396Y278426D01*
X1320051Y278065D01*
X1319821Y277548D01*
X1319744Y277083D01*
X1321354D01*
G01X1302308Y287000D02*
Y300800D01*
G01X1319746Y70100D02*
Y59900D01*
X1315146D01*
Y70100D01*
X1319746D01*
G01Y114500D02*
Y104300D01*
X1315146D01*
Y114500D01*
X1319746D01*
G01Y158900D02*
Y148700D01*
X1315146D01*
Y158900D01*
X1319746D01*
G01Y203300D02*
Y193100D01*
X1315146D01*
Y203300D01*
X1319746D01*
G01Y247700D02*
Y237500D01*
X1315146D01*
Y247700D01*
X1319746D01*
G01Y292100D02*
Y281900D01*
X1315146D01*
Y292100D01*
X1319746D01*
G01X1335345Y321500D02*
Y324600D01*
G01X1336955D02*
Y321500D01*
G01Y323050D02*
X1335345D01*
G01X1339250Y321500D02*
Y324600D01*
X1338790Y323980D01*
G01Y321500D02*
X1339710D01*
G01X1342350Y324600D02*
X1342043Y324497D01*
X1341813Y324238D01*
X1341660Y323928D01*
X1341545Y323515D01*
X1341507Y323050D01*
X1341545Y322585D01*
X1341660Y322172D01*
X1341813Y321862D01*
X1342043Y321603D01*
X1342350Y321500D01*
X1342657Y321603D01*
X1342887Y321862D01*
X1343040Y322172D01*
X1343155Y322585D01*
X1343193Y323050D01*
X1343155Y323515D01*
X1343040Y323928D01*
X1342887Y324238D01*
X1342657Y324497D01*
X1342350Y324600D01*
G01X1499862Y1240D02*
Y29784D01*
X1422973D01*
Y1240D01*
X1499862D01*
G01X1411162Y3000D02*
Y41595D01*
X1435700D01*
G01X1414345Y534000D02*
Y537100D01*
G01X1415955D02*
Y534000D01*
G01Y535550D02*
X1414345D01*
G01X1418250Y534000D02*
Y537100D01*
X1417790Y536480D01*
G01Y534000D02*
X1418710D01*
G01X1421350D02*
Y537100D01*
X1420890Y536480D01*
G01Y534000D02*
X1421810D01*
G01X1436133Y593000D02*
Y598000D01*
X1437653D01*
X1438160Y597750D01*
X1438540Y597167D01*
X1438667Y596500D01*
X1438540Y595833D01*
X1438223Y595333D01*
X1437653Y595083D01*
X1436133D01*
G01X1441233Y593000D02*
Y598000D01*
X1442817D01*
X1443323Y597750D01*
X1443640Y597417D01*
X1443767Y596750D01*
X1443640Y596083D01*
X1443260Y595667D01*
X1442817Y595417D01*
X1441233D01*
G01X1442817D02*
X1443767Y593000D01*
G01X1448867D02*
X1446333D01*
Y598000D01*
X1448867D01*
G01X1447853Y595583D02*
X1446333D01*
G01X1451370Y593667D02*
X1451877Y593250D01*
X1452447Y593000D01*
X1452953D01*
X1453460Y593250D01*
X1453840Y593667D01*
X1454030Y594250D01*
X1453903Y594833D01*
X1453587Y595333D01*
X1453017Y595667D01*
X1452257Y595833D01*
X1451813Y596167D01*
X1451623Y596750D01*
X1451750Y597333D01*
X1452067Y597750D01*
X1452510Y598000D01*
X1452953D01*
X1453397Y597833D01*
X1453777Y597417D01*
G01X1456470Y593667D02*
X1456977Y593250D01*
X1457547Y593000D01*
X1458053D01*
X1458560Y593250D01*
X1458940Y593667D01*
X1459130Y594250D01*
X1459003Y594833D01*
X1458687Y595333D01*
X1458117Y595667D01*
X1457357Y595833D01*
X1456913Y596167D01*
X1456723Y596750D01*
X1456850Y597333D01*
X1457167Y597750D01*
X1457610Y598000D01*
X1458053D01*
X1458497Y597833D01*
X1458877Y597417D01*
G01X1462077Y594667D02*
X1463723D01*
G01X1466797Y593000D02*
Y598000D01*
X1469203D01*
G01X1468317Y595583D02*
X1466797D01*
G01X1472340Y598000D02*
X1473860D01*
G01X1473100D02*
Y593000D01*
G01X1472340D02*
X1473860D01*
G01X1478200Y598000D02*
Y593000D01*
G01X1476743Y598000D02*
X1479657D01*
G01X1409744Y590473D02*
Y729449D01*
G01X1503642Y590473D02*
X1409744D01*
G01X1423441Y615999D02*
X1423671Y615844D01*
X1423939Y615741D01*
X1424246D01*
X1424591Y615896D01*
X1424859Y616154D01*
X1425051Y616464D01*
X1425204Y616981D01*
X1425242Y617446D01*
X1425166Y617911D01*
X1425051Y618221D01*
X1424821Y618531D01*
X1424552Y618738D01*
X1424284Y618841D01*
X1424016D01*
X1423747Y618738D01*
X1423517Y618583D01*
X1423326Y618376D01*
G01X1421912Y617549D02*
X1421644Y617188D01*
X1421414Y616981D01*
X1421107Y616878D01*
X1420839Y616981D01*
X1420647Y617188D01*
X1420494Y617498D01*
X1420456Y617859D01*
X1420494Y618169D01*
X1420647Y618479D01*
X1420877Y618738D01*
X1421146Y618841D01*
X1421452Y618738D01*
X1421721Y618428D01*
X1421874Y617963D01*
X1421912Y617446D01*
X1421836Y616774D01*
X1421721Y616413D01*
X1421529Y616051D01*
X1421261Y615793D01*
X1420992Y615741D01*
X1420724Y615844D01*
X1420532Y616103D01*
G01X1423441Y623873D02*
X1423671Y623718D01*
X1423939Y623615D01*
X1424246D01*
X1424591Y623770D01*
X1424859Y624028D01*
X1425051Y624338D01*
X1425204Y624855D01*
X1425242Y625320D01*
X1425166Y625785D01*
X1425051Y626095D01*
X1424821Y626405D01*
X1424552Y626612D01*
X1424284Y626715D01*
X1424016D01*
X1423747Y626612D01*
X1423517Y626457D01*
X1423326Y626250D01*
G01X1422027D02*
X1421797Y626508D01*
X1421529Y626663D01*
X1421184Y626715D01*
X1420839Y626612D01*
X1420571Y626405D01*
X1420379Y626043D01*
X1420341Y625630D01*
X1420417Y625217D01*
X1420609Y624958D01*
X1420877Y624752D01*
X1421146Y624700D01*
X1421414Y624752D01*
X1421759Y624958D01*
X1421644Y623615D01*
X1420609D01*
G01X1423441Y631747D02*
X1423671Y631592D01*
X1423939Y631489D01*
X1424246D01*
X1424591Y631644D01*
X1424859Y631902D01*
X1425051Y632212D01*
X1425204Y632729D01*
X1425242Y633194D01*
X1425166Y633659D01*
X1425051Y633969D01*
X1424821Y634279D01*
X1424552Y634486D01*
X1424284Y634589D01*
X1424016D01*
X1423747Y634486D01*
X1423517Y634331D01*
X1423326Y634124D01*
G01X1420724Y634589D02*
Y631489D01*
X1422142Y633711D01*
X1420226D01*
G01X1421555Y602284D02*
X1491831D01*
Y717638D01*
X1421555D01*
Y602284D01*
G01X1425127Y650337D02*
Y647237D01*
X1424361D01*
X1424054Y647392D01*
X1423824Y647599D01*
X1423632Y647909D01*
X1423479Y648270D01*
X1423441Y648787D01*
X1423479Y649304D01*
X1423632Y649665D01*
X1423824Y649975D01*
X1424054Y650182D01*
X1424361Y650337D01*
X1425127D01*
G01X1421912Y649045D02*
X1421644Y648684D01*
X1421414Y648477D01*
X1421107Y648374D01*
X1420839Y648477D01*
X1420647Y648684D01*
X1420494Y648994D01*
X1420456Y649355D01*
X1420494Y649665D01*
X1420647Y649975D01*
X1420877Y650234D01*
X1421146Y650337D01*
X1421452Y650234D01*
X1421721Y649924D01*
X1421874Y649459D01*
X1421912Y648942D01*
X1421836Y648270D01*
X1421721Y647909D01*
X1421529Y647547D01*
X1421261Y647289D01*
X1420992Y647237D01*
X1420724Y647340D01*
X1420532Y647599D01*
G01X1425127Y658211D02*
Y655111D01*
X1424361D01*
X1424054Y655266D01*
X1423824Y655473D01*
X1423632Y655783D01*
X1423479Y656144D01*
X1423441Y656661D01*
X1423479Y657178D01*
X1423632Y657539D01*
X1423824Y657849D01*
X1424054Y658056D01*
X1424361Y658211D01*
X1425127D01*
G01X1422027Y657746D02*
X1421797Y658004D01*
X1421529Y658159D01*
X1421184Y658211D01*
X1420839Y658108D01*
X1420571Y657901D01*
X1420379Y657539D01*
X1420341Y657126D01*
X1420417Y656713D01*
X1420609Y656454D01*
X1420877Y656248D01*
X1421146Y656196D01*
X1421414Y656248D01*
X1421759Y656454D01*
X1421644Y655111D01*
X1420609D01*
G01X1425127Y666085D02*
Y662985D01*
X1424361D01*
X1424054Y663140D01*
X1423824Y663347D01*
X1423632Y663657D01*
X1423479Y664018D01*
X1423441Y664535D01*
X1423479Y665052D01*
X1423632Y665413D01*
X1423824Y665723D01*
X1424054Y665930D01*
X1424361Y666085D01*
X1425127D01*
G01X1420724D02*
Y662985D01*
X1422142Y665207D01*
X1420226D01*
G01X1421555Y676496D02*
X1491831D01*
G01X1409744Y729449D02*
X1503642D01*
G01X1466633Y33000D02*
Y38000D01*
X1468153D01*
X1468660Y37750D01*
X1469040Y37167D01*
X1469167Y36500D01*
X1469040Y35833D01*
X1468723Y35333D01*
X1468153Y35083D01*
X1466633D01*
G01X1471733Y33000D02*
Y38000D01*
X1473317D01*
X1473823Y37750D01*
X1474140Y37417D01*
X1474267Y36750D01*
X1474140Y36083D01*
X1473760Y35667D01*
X1473317Y35417D01*
X1471733D01*
G01X1473317D02*
X1474267Y33000D01*
G01X1479367D02*
X1476833D01*
Y38000D01*
X1479367D01*
G01X1478353Y35583D02*
X1476833D01*
G01X1481870Y33667D02*
X1482377Y33250D01*
X1482947Y33000D01*
X1483453D01*
X1483960Y33250D01*
X1484340Y33667D01*
X1484530Y34250D01*
X1484403Y34833D01*
X1484087Y35333D01*
X1483517Y35667D01*
X1482757Y35833D01*
X1482313Y36167D01*
X1482123Y36750D01*
X1482250Y37333D01*
X1482567Y37750D01*
X1483010Y38000D01*
X1483453D01*
X1483897Y37833D01*
X1484277Y37417D01*
G01X1486970Y33667D02*
X1487477Y33250D01*
X1488047Y33000D01*
X1488553D01*
X1489060Y33250D01*
X1489440Y33667D01*
X1489630Y34250D01*
X1489503Y34833D01*
X1489187Y35333D01*
X1488617Y35667D01*
X1487857Y35833D01*
X1487413Y36167D01*
X1487223Y36750D01*
X1487350Y37333D01*
X1487667Y37750D01*
X1488110Y38000D01*
X1488553D01*
X1488997Y37833D01*
X1489377Y37417D01*
G01X1492577Y34667D02*
X1494223D01*
G01X1497297Y33000D02*
Y38000D01*
X1499703D01*
G01X1498817Y35583D02*
X1497297D01*
G01X1502840Y38000D02*
X1504360D01*
G01X1503600D02*
Y33000D01*
G01X1502840D02*
X1504360D01*
G01X1508700Y38000D02*
Y33000D01*
G01X1507243Y38000D02*
X1510157D01*
G01X1448845Y93000D02*
Y96100D01*
G01X1450455D02*
Y93000D01*
G01Y94550D02*
X1448845D01*
G01X1452750Y93000D02*
Y96100D01*
X1452290Y95480D01*
G01Y93000D02*
X1453210D01*
G01X1455122Y95583D02*
X1455352Y95893D01*
X1455620Y96048D01*
X1455927Y96100D01*
X1456310Y95997D01*
X1456578Y95738D01*
X1456655Y95428D01*
X1456617Y95118D01*
X1456463Y94860D01*
X1455697Y94343D01*
X1455352Y93982D01*
X1455122Y93465D01*
X1455045Y93000D01*
X1456655D01*
G01X1524917Y215236D02*
G03I-36417J0D01*
G01X1488500D02*
X1452068D01*
X1524917D01*
G01Y295236D02*
G03I-36417J0D01*
G01X1488500D02*
X1452068D01*
X1524917D01*
G01Y375236D02*
G03I-36417J0D01*
G01X1488500D02*
X1452068D01*
X1524917D01*
G01Y455236D02*
G03I-36417J0D01*
G01X1488500D02*
X1452068D01*
X1524917D01*
G01Y535236D02*
G03I-36417J0D01*
G01X1488500D02*
X1452068D01*
X1524917D01*
G01X1456880Y579000D02*
X1458147D01*
Y577500D01*
X1457767Y577000D01*
X1457323Y576667D01*
X1456690Y576500D01*
X1456057Y576667D01*
X1455613Y577000D01*
X1455233Y577500D01*
X1454980Y578083D01*
X1454853Y578750D01*
Y579333D01*
X1454980Y579833D01*
X1455233Y580417D01*
X1455613Y580917D01*
X1455993Y581250D01*
X1456500Y581500D01*
X1456943D01*
X1457450Y581333D01*
X1457830Y581000D01*
G01X1460333Y576500D02*
Y581500D01*
X1461853D01*
X1462360Y581250D01*
X1462740Y580667D01*
X1462867Y580000D01*
X1462740Y579333D01*
X1462423Y578833D01*
X1461853Y578583D01*
X1460333D01*
G01X1465307Y581500D02*
Y577917D01*
X1465560Y577167D01*
X1466067Y576667D01*
X1466700Y576500D01*
X1467333Y576667D01*
X1467840Y577167D01*
X1468093Y577917D01*
Y581500D01*
G01X1475633Y576500D02*
Y581500D01*
X1477153D01*
X1477660Y581250D01*
X1478040Y580667D01*
X1478167Y580000D01*
X1478040Y579333D01*
X1477723Y578833D01*
X1477153Y578583D01*
X1475633D01*
G01X1482000Y576500D02*
X1481493Y576583D01*
X1481050Y576917D01*
X1480670Y577417D01*
X1480417Y578000D01*
X1480290Y578667D01*
Y579333D01*
X1480417Y580000D01*
X1480670Y580583D01*
X1481050Y581083D01*
X1481493Y581417D01*
X1482000Y581500D01*
X1482507Y581417D01*
X1482950Y581083D01*
X1483330Y580583D01*
X1483583Y580000D01*
X1483710Y579333D01*
Y578667D01*
X1483583Y578000D01*
X1483330Y577417D01*
X1482950Y576917D01*
X1482507Y576583D01*
X1482000Y576500D01*
G01X1485200Y581500D02*
X1486087Y576500D01*
X1487100Y581500D01*
X1488113Y576500D01*
X1489000Y581500D01*
G01X1493467Y576500D02*
X1490933D01*
Y581500D01*
X1493467D01*
G01X1492453Y579083D02*
X1490933D01*
G01X1496033Y576500D02*
Y581500D01*
X1497617D01*
X1498123Y581250D01*
X1498440Y580917D01*
X1498567Y580250D01*
X1498440Y579583D01*
X1498060Y579167D01*
X1497617Y578917D01*
X1496033D01*
G01X1497617D02*
X1498567Y576500D01*
G01X1508893Y581083D02*
X1508513Y581333D01*
X1508070Y581500D01*
X1507563D01*
X1506993Y581250D01*
X1506550Y580833D01*
X1506233Y580333D01*
X1505980Y579500D01*
X1505917Y578750D01*
X1506043Y578000D01*
X1506233Y577500D01*
X1506613Y577000D01*
X1507057Y576667D01*
X1507500Y576500D01*
X1507943D01*
X1508387Y576667D01*
X1508767Y576917D01*
X1509083Y577250D01*
G01X1512600Y576500D02*
X1512093Y576583D01*
X1511650Y576917D01*
X1511270Y577417D01*
X1511017Y578000D01*
X1510890Y578667D01*
Y579333D01*
X1511017Y580000D01*
X1511270Y580583D01*
X1511650Y581083D01*
X1512093Y581417D01*
X1512600Y581500D01*
X1513107Y581417D01*
X1513550Y581083D01*
X1513930Y580583D01*
X1514183Y580000D01*
X1514310Y579333D01*
Y578667D01*
X1514183Y578000D01*
X1513930Y577417D01*
X1513550Y576917D01*
X1513107Y576583D01*
X1512600Y576500D01*
G01X1516243D02*
Y581500D01*
X1519157Y576500D01*
Y581500D01*
G01X1521343Y576500D02*
Y581500D01*
X1524257Y576500D01*
Y581500D01*
G01X1453000Y582000D02*
Y575000D01*
X1526000D01*
Y583500D01*
X1453000D01*
Y582000D01*
G01X1454383Y586620D02*
X1454575Y586310D01*
X1454805Y586103D01*
X1455073Y586000D01*
X1455380Y586103D01*
X1455610Y586310D01*
X1455840Y586620D01*
X1455917Y587033D01*
Y589100D01*
G01X1457522Y588583D02*
X1457752Y588893D01*
X1458020Y589048D01*
X1458327Y589100D01*
X1458710Y588997D01*
X1458978Y588738D01*
X1459055Y588428D01*
X1459017Y588118D01*
X1458863Y587860D01*
X1458097Y587343D01*
X1457752Y586982D01*
X1457522Y586465D01*
X1457445Y586000D01*
X1459055D01*
G01X1468800Y41595D02*
X1511673D01*
G01X1491828Y73601D02*
Y67401D01*
X1488628D01*
Y73601D01*
X1491828D01*
G01X1496328D02*
Y67401D01*
X1493128D01*
Y73601D01*
X1496328D01*
G01X1501500Y103327D02*
Y101087D01*
G01X1503125Y102300D02*
X1499875D01*
G01X1488233Y104583D02*
X1485133D01*
Y105503D01*
X1485288Y105810D01*
X1485650Y106040D01*
X1486063Y106117D01*
X1486476Y106040D01*
X1486786Y105848D01*
X1486941Y105503D01*
Y104583D01*
G01X1488233Y107607D02*
X1485133D01*
Y108373D01*
X1485288Y108680D01*
X1485495Y108910D01*
X1485805Y109102D01*
X1486166Y109255D01*
X1486683Y109293D01*
X1487200Y109255D01*
X1487561Y109102D01*
X1487871Y108910D01*
X1488078Y108680D01*
X1488233Y108373D01*
Y107607D01*
G01Y111550D02*
X1488181Y111818D01*
X1488026Y112125D01*
X1487768Y112317D01*
X1487406Y112393D01*
X1487045Y112317D01*
X1486735Y112087D01*
X1486580Y111742D01*
Y111358D01*
X1486476Y111128D01*
X1486218Y110937D01*
X1485856Y110860D01*
X1485495Y110975D01*
X1485236Y111243D01*
X1485133Y111550D01*
X1485236Y111857D01*
X1485495Y112125D01*
X1485856Y112240D01*
X1486218Y112163D01*
X1486476Y111972D01*
X1486580Y111742D01*
Y111358D01*
X1486735Y111013D01*
X1487045Y110783D01*
X1487406Y110707D01*
X1487768Y110783D01*
X1488026Y110975D01*
X1488181Y111282D01*
X1488233Y111550D01*
G01X1501600Y104000D02*
X1489356D01*
Y142000D01*
X1501600D01*
G01Y147713D02*
Y145287D01*
G01X1513844Y143500D02*
X1489356D01*
G01X1513844Y142800D02*
X1489356D01*
G01X1513844Y142400D02*
X1489356D01*
G01X1513844Y143200D02*
X1489356D01*
G01Y141950D02*
Y144050D01*
G01X1501600Y144000D02*
X1489356D01*
G01X1507100Y127500D02*
X1496100D01*
G01X1489271Y590473D02*
Y729449D01*
G01X1559547Y590473D02*
X1489271D01*
G01X1498160Y634389D02*
X1497202Y631289D01*
X1496244Y634389D01*
G01X1496589Y633304D02*
X1497815D01*
G01X1494945Y633769D02*
X1494715Y634131D01*
X1494409Y634337D01*
X1494064Y634389D01*
X1493757Y634337D01*
X1493450Y634079D01*
X1493259Y633769D01*
X1493220Y633459D01*
X1493297Y633097D01*
X1493565Y632839D01*
X1493834Y632736D01*
X1494179D01*
G01X1493834D02*
X1493604Y632581D01*
X1493412Y632322D01*
X1493335Y632012D01*
X1493412Y631702D01*
X1493604Y631444D01*
X1493949Y631289D01*
X1494294Y631341D01*
X1494639Y631547D01*
G01X1498160Y626515D02*
X1497202Y623415D01*
X1496244Y626515D01*
G01X1496589Y625430D02*
X1497815D01*
G01X1494830Y623932D02*
X1494600Y623622D01*
X1494332Y623467D01*
X1494025Y623415D01*
X1493642Y623518D01*
X1493374Y623777D01*
X1493297Y624087D01*
X1493335Y624397D01*
X1493489Y624655D01*
X1494255Y625172D01*
X1494600Y625533D01*
X1494830Y626050D01*
X1494907Y626515D01*
X1493297D01*
G01X1497930Y650137D02*
Y647037D01*
X1496474D01*
G01X1497010Y648535D02*
X1497930D01*
G01X1494102Y650137D02*
Y647037D01*
X1494562Y647657D01*
G01Y650137D02*
X1493642D01*
G01X1497930Y658011D02*
Y654911D01*
X1496474D01*
G01X1497010Y656409D02*
X1497930D01*
G01X1494830Y655428D02*
X1494600Y655118D01*
X1494332Y654963D01*
X1494025Y654911D01*
X1493642Y655014D01*
X1493374Y655273D01*
X1493297Y655583D01*
X1493335Y655893D01*
X1493489Y656151D01*
X1494255Y656668D01*
X1494600Y657029D01*
X1494830Y657546D01*
X1494907Y658011D01*
X1493297D01*
G01X1497930Y665885D02*
Y662785D01*
X1496474D01*
G01X1497010Y664283D02*
X1497930D01*
G01X1494945Y665265D02*
X1494715Y665627D01*
X1494409Y665833D01*
X1494064Y665885D01*
X1493757Y665833D01*
X1493450Y665575D01*
X1493259Y665265D01*
X1493220Y664955D01*
X1493297Y664593D01*
X1493565Y664335D01*
X1493834Y664232D01*
X1494179D01*
G01X1493834D02*
X1493604Y664077D01*
X1493412Y663818D01*
X1493335Y663508D01*
X1493412Y663198D01*
X1493604Y662940D01*
X1493949Y662785D01*
X1494294Y662837D01*
X1494639Y663043D01*
G01X1489271Y729449D02*
X1559547D01*
G01X1515797Y17500D02*
Y22500D01*
X1518203D01*
G01X1517317Y20083D02*
X1515797D01*
G01X1520517Y17500D02*
X1522100Y22500D01*
X1523683Y17500D01*
G01X1523113Y19250D02*
X1521087D01*
G01X1525743Y17500D02*
Y22500D01*
X1528657Y17500D01*
Y22500D01*
G01X1530400Y15833D02*
X1534200D01*
G01X1537907Y20167D02*
X1538160Y20417D01*
X1538350Y20833D01*
X1538477Y21417D01*
X1538350Y21917D01*
X1538097Y22250D01*
X1537653Y22500D01*
X1535943D01*
Y17500D01*
X1538033D01*
X1538477Y17833D01*
X1538730Y18333D01*
X1538857Y18917D01*
X1538730Y19500D01*
X1538350Y20000D01*
X1537907Y20167D01*
X1535943D01*
G01X1541233Y17500D02*
Y22500D01*
X1542753D01*
X1543260Y22250D01*
X1543640Y21667D01*
X1543767Y21000D01*
X1543640Y20333D01*
X1543323Y19833D01*
X1542753Y19583D01*
X1541233D01*
G01X1545700Y15833D02*
X1549500D01*
G01X1552700Y17500D02*
Y22500D01*
X1551940Y21500D01*
G01Y17500D02*
X1553460D01*
G01X1511673Y41595D02*
Y1500D01*
G01X1503683Y44620D02*
X1503875Y44310D01*
X1504105Y44103D01*
X1504373Y44000D01*
X1504680Y44103D01*
X1504910Y44310D01*
X1505140Y44620D01*
X1505217Y45033D01*
Y47100D01*
G01X1507550Y44000D02*
X1507818Y44052D01*
X1508125Y44207D01*
X1508317Y44465D01*
X1508393Y44827D01*
X1508317Y45188D01*
X1508087Y45498D01*
X1507742Y45653D01*
X1507358D01*
X1507128Y45757D01*
X1506937Y46015D01*
X1506860Y46377D01*
X1506975Y46738D01*
X1507243Y46997D01*
X1507550Y47100D01*
X1507857Y46997D01*
X1508125Y46738D01*
X1508240Y46377D01*
X1508163Y46015D01*
X1507972Y45757D01*
X1507742Y45653D01*
X1507358D01*
X1507013Y45498D01*
X1506783Y45188D01*
X1506707Y44827D01*
X1506783Y44465D01*
X1506975Y44207D01*
X1507282Y44052D01*
X1507550Y44000D01*
G01X1525945Y64500D02*
Y67600D01*
G01X1527555D02*
Y64500D01*
G01Y66050D02*
X1525945D01*
G01X1529122Y67083D02*
X1529352Y67393D01*
X1529620Y67548D01*
X1529927Y67600D01*
X1530310Y67497D01*
X1530578Y67238D01*
X1530655Y66928D01*
X1530617Y66618D01*
X1530463Y66360D01*
X1529697Y65843D01*
X1529352Y65482D01*
X1529122Y64965D01*
X1529045Y64500D01*
X1530655D01*
G01X1532873D02*
X1532950Y65172D01*
X1533065Y65740D01*
X1533218Y66257D01*
X1533410Y66825D01*
X1533717Y67600D01*
X1532183D01*
G01X1538550Y78500D02*
G03I-9450J0D01*
G01X1497628Y67401D02*
Y73601D01*
X1500828D01*
Y67401D01*
X1497628D01*
G01X1502128D02*
Y73601D01*
X1505328D01*
Y67401D01*
X1502128D01*
G01X1521000Y100883D02*
X1517900D01*
Y101803D01*
X1518055Y102110D01*
X1518417Y102340D01*
X1518830Y102417D01*
X1519243Y102340D01*
X1519553Y102148D01*
X1519708Y101803D01*
Y100883D01*
G01X1521000Y104750D02*
X1520948Y104443D01*
X1520742Y104175D01*
X1520432Y103945D01*
X1520070Y103792D01*
X1519657Y103715D01*
X1519243D01*
X1518830Y103792D01*
X1518468Y103945D01*
X1518158Y104175D01*
X1517952Y104443D01*
X1517900Y104750D01*
X1517952Y105057D01*
X1518158Y105325D01*
X1518468Y105555D01*
X1518830Y105708D01*
X1519243Y105785D01*
X1519657D01*
X1520070Y105708D01*
X1520432Y105555D01*
X1520742Y105325D01*
X1520948Y105057D01*
X1521000Y104750D01*
G01X1520173Y105057D02*
X1521000Y105517D01*
G01Y107850D02*
X1517900D01*
X1518520Y107390D01*
G01X1521000D02*
Y108310D01*
G01Y110873D02*
X1520328Y110950D01*
X1519760Y111065D01*
X1519243Y111218D01*
X1518675Y111410D01*
X1517900Y111717D01*
Y110183D01*
G01X1520400Y116100D02*
X1526600D01*
Y112900D01*
X1520400D01*
Y116100D01*
G01X1522900Y97400D02*
Y103600D01*
X1526100D01*
Y97400D01*
X1522900D01*
G01X1513844Y142000D02*
Y104000D01*
X1501600D01*
G01Y118700D02*
Y116300D01*
G01Y127500D02*
X1497600Y119000D01*
X1505600D01*
X1501600Y127000D01*
G01X1513844Y144000D02*
Y141950D01*
G01X1501600Y142000D02*
X1513844D01*
G01X1501600Y127500D02*
Y130100D01*
G01X1513844Y144000D02*
X1501600D01*
G01X1510983Y247000D02*
Y250100D01*
X1511903D01*
X1512210Y249945D01*
X1512440Y249583D01*
X1512517Y249170D01*
X1512440Y248757D01*
X1512248Y248447D01*
X1511903Y248292D01*
X1510983D01*
G01X1515693Y249842D02*
X1515463Y249997D01*
X1515195Y250100D01*
X1514888D01*
X1514543Y249945D01*
X1514275Y249687D01*
X1514083Y249377D01*
X1513930Y248860D01*
X1513892Y248395D01*
X1513968Y247930D01*
X1514083Y247620D01*
X1514313Y247310D01*
X1514582Y247103D01*
X1514850Y247000D01*
X1515118D01*
X1515387Y247103D01*
X1515617Y247258D01*
X1515808Y247465D01*
G01X1518410Y247000D02*
Y250100D01*
X1516992Y247878D01*
X1518908D01*
G01X1520322Y249583D02*
X1520552Y249893D01*
X1520820Y250048D01*
X1521127Y250100D01*
X1521510Y249997D01*
X1521778Y249738D01*
X1521855Y249428D01*
X1521817Y249118D01*
X1521663Y248860D01*
X1520897Y248343D01*
X1520552Y247982D01*
X1520322Y247465D01*
X1520245Y247000D01*
X1521855D01*
G01X1508983Y327500D02*
Y330600D01*
X1509903D01*
X1510210Y330445D01*
X1510440Y330083D01*
X1510517Y329670D01*
X1510440Y329257D01*
X1510248Y328947D01*
X1509903Y328792D01*
X1508983D01*
G01X1513693Y330342D02*
X1513463Y330497D01*
X1513195Y330600D01*
X1512888D01*
X1512543Y330445D01*
X1512275Y330187D01*
X1512083Y329877D01*
X1511930Y329360D01*
X1511892Y328895D01*
X1511968Y328430D01*
X1512083Y328120D01*
X1512313Y327810D01*
X1512582Y327603D01*
X1512850Y327500D01*
X1513118D01*
X1513387Y327603D01*
X1513617Y327758D01*
X1513808Y327965D01*
G01X1516410Y327500D02*
Y330600D01*
X1514992Y328378D01*
X1516908D01*
G01X1519050Y330600D02*
X1518743Y330497D01*
X1518513Y330238D01*
X1518360Y329928D01*
X1518245Y329515D01*
X1518207Y329050D01*
X1518245Y328585D01*
X1518360Y328172D01*
X1518513Y327862D01*
X1518743Y327603D01*
X1519050Y327500D01*
X1519357Y327603D01*
X1519587Y327862D01*
X1519740Y328172D01*
X1519855Y328585D01*
X1519893Y329050D01*
X1519855Y329515D01*
X1519740Y329928D01*
X1519587Y330238D01*
X1519357Y330497D01*
X1519050Y330600D01*
G01X1508983Y407500D02*
Y410600D01*
X1509903D01*
X1510210Y410445D01*
X1510440Y410083D01*
X1510517Y409670D01*
X1510440Y409257D01*
X1510248Y408947D01*
X1509903Y408792D01*
X1508983D01*
G01X1513693Y410342D02*
X1513463Y410497D01*
X1513195Y410600D01*
X1512888D01*
X1512543Y410445D01*
X1512275Y410187D01*
X1512083Y409877D01*
X1511930Y409360D01*
X1511892Y408895D01*
X1511968Y408430D01*
X1512083Y408120D01*
X1512313Y407810D01*
X1512582Y407603D01*
X1512850Y407500D01*
X1513118D01*
X1513387Y407603D01*
X1513617Y407758D01*
X1513808Y407965D01*
G01X1515107Y408120D02*
X1515337Y407758D01*
X1515643Y407552D01*
X1515988Y407500D01*
X1516295Y407552D01*
X1516602Y407810D01*
X1516793Y408120D01*
X1516832Y408430D01*
X1516755Y408792D01*
X1516487Y409050D01*
X1516218Y409153D01*
X1515873D01*
G01X1516218D02*
X1516448Y409308D01*
X1516640Y409567D01*
X1516717Y409877D01*
X1516640Y410187D01*
X1516448Y410445D01*
X1516103Y410600D01*
X1515758Y410548D01*
X1515413Y410342D01*
G01X1518322Y410083D02*
X1518552Y410393D01*
X1518820Y410548D01*
X1519127Y410600D01*
X1519510Y410497D01*
X1519778Y410238D01*
X1519855Y409928D01*
X1519817Y409618D01*
X1519663Y409360D01*
X1518897Y408843D01*
X1518552Y408482D01*
X1518322Y407965D01*
X1518245Y407500D01*
X1519855D01*
G01X1509983Y487000D02*
Y490100D01*
X1510903D01*
X1511210Y489945D01*
X1511440Y489583D01*
X1511517Y489170D01*
X1511440Y488757D01*
X1511248Y488447D01*
X1510903Y488292D01*
X1509983D01*
G01X1514693Y489842D02*
X1514463Y489997D01*
X1514195Y490100D01*
X1513888D01*
X1513543Y489945D01*
X1513275Y489687D01*
X1513083Y489377D01*
X1512930Y488860D01*
X1512892Y488395D01*
X1512968Y487930D01*
X1513083Y487620D01*
X1513313Y487310D01*
X1513582Y487103D01*
X1513850Y487000D01*
X1514118D01*
X1514387Y487103D01*
X1514617Y487258D01*
X1514808Y487465D01*
G01X1516107Y487620D02*
X1516337Y487258D01*
X1516643Y487052D01*
X1516988Y487000D01*
X1517295Y487052D01*
X1517602Y487310D01*
X1517793Y487620D01*
X1517832Y487930D01*
X1517755Y488292D01*
X1517487Y488550D01*
X1517218Y488653D01*
X1516873D01*
G01X1517218D02*
X1517448Y488808D01*
X1517640Y489067D01*
X1517717Y489377D01*
X1517640Y489687D01*
X1517448Y489945D01*
X1517103Y490100D01*
X1516758Y490048D01*
X1516413Y489842D01*
G01X1520050Y490100D02*
X1519743Y489997D01*
X1519513Y489738D01*
X1519360Y489428D01*
X1519245Y489015D01*
X1519207Y488550D01*
X1519245Y488085D01*
X1519360Y487672D01*
X1519513Y487362D01*
X1519743Y487103D01*
X1520050Y487000D01*
X1520357Y487103D01*
X1520587Y487362D01*
X1520740Y487672D01*
X1520855Y488085D01*
X1520893Y488550D01*
X1520855Y489015D01*
X1520740Y489428D01*
X1520587Y489738D01*
X1520357Y489997D01*
X1520050Y490100D01*
G01X1506483Y569000D02*
Y572100D01*
X1507403D01*
X1507710Y571945D01*
X1507940Y571583D01*
X1508017Y571170D01*
X1507940Y570757D01*
X1507748Y570447D01*
X1507403Y570292D01*
X1506483D01*
G01X1511193Y571842D02*
X1510963Y571997D01*
X1510695Y572100D01*
X1510388D01*
X1510043Y571945D01*
X1509775Y571687D01*
X1509583Y571377D01*
X1509430Y570860D01*
X1509392Y570395D01*
X1509468Y569930D01*
X1509583Y569620D01*
X1509813Y569310D01*
X1510082Y569103D01*
X1510350Y569000D01*
X1510618D01*
X1510887Y569103D01*
X1511117Y569258D01*
X1511308Y569465D01*
G01X1512722Y571583D02*
X1512952Y571893D01*
X1513220Y572048D01*
X1513527Y572100D01*
X1513910Y571997D01*
X1514178Y571738D01*
X1514255Y571428D01*
X1514217Y571118D01*
X1514063Y570860D01*
X1513297Y570343D01*
X1512952Y569982D01*
X1512722Y569465D01*
X1512645Y569000D01*
X1514255D01*
G01X1516550D02*
X1516818Y569052D01*
X1517125Y569207D01*
X1517317Y569465D01*
X1517393Y569827D01*
X1517317Y570188D01*
X1517087Y570498D01*
X1516742Y570653D01*
X1516358D01*
X1516128Y570757D01*
X1515937Y571015D01*
X1515860Y571377D01*
X1515975Y571738D01*
X1516243Y571997D01*
X1516550Y572100D01*
X1516857Y571997D01*
X1517125Y571738D01*
X1517240Y571377D01*
X1517163Y571015D01*
X1516972Y570757D01*
X1516742Y570653D01*
X1516358D01*
X1516013Y570498D01*
X1515783Y570188D01*
X1515707Y569827D01*
X1515783Y569465D01*
X1515975Y569207D01*
X1516282Y569052D01*
X1516550Y569000D01*
G01X1524883Y586120D02*
X1525075Y585810D01*
X1525305Y585603D01*
X1525573Y585500D01*
X1525880Y585603D01*
X1526110Y585810D01*
X1526340Y586120D01*
X1526417Y586533D01*
Y588600D01*
G01X1528750Y585500D02*
Y588600D01*
X1528290Y587980D01*
G01Y585500D02*
X1529210D01*
G01X1503133Y593000D02*
Y598000D01*
X1504653D01*
X1505160Y597750D01*
X1505540Y597167D01*
X1505667Y596500D01*
X1505540Y595833D01*
X1505223Y595333D01*
X1504653Y595083D01*
X1503133D01*
G01X1508233Y593000D02*
Y598000D01*
X1509817D01*
X1510323Y597750D01*
X1510640Y597417D01*
X1510767Y596750D01*
X1510640Y596083D01*
X1510260Y595667D01*
X1509817Y595417D01*
X1508233D01*
G01X1509817D02*
X1510767Y593000D01*
G01X1515867D02*
X1513333D01*
Y598000D01*
X1515867D01*
G01X1514853Y595583D02*
X1513333D01*
G01X1518370Y593667D02*
X1518877Y593250D01*
X1519447Y593000D01*
X1519953D01*
X1520460Y593250D01*
X1520840Y593667D01*
X1521030Y594250D01*
X1520903Y594833D01*
X1520587Y595333D01*
X1520017Y595667D01*
X1519257Y595833D01*
X1518813Y596167D01*
X1518623Y596750D01*
X1518750Y597333D01*
X1519067Y597750D01*
X1519510Y598000D01*
X1519953D01*
X1520397Y597833D01*
X1520777Y597417D01*
G01X1523470Y593667D02*
X1523977Y593250D01*
X1524547Y593000D01*
X1525053D01*
X1525560Y593250D01*
X1525940Y593667D01*
X1526130Y594250D01*
X1526003Y594833D01*
X1525687Y595333D01*
X1525117Y595667D01*
X1524357Y595833D01*
X1523913Y596167D01*
X1523723Y596750D01*
X1523850Y597333D01*
X1524167Y597750D01*
X1524610Y598000D01*
X1525053D01*
X1525497Y597833D01*
X1525877Y597417D01*
G01X1529077Y594667D02*
X1530723D01*
G01X1533797Y593000D02*
Y598000D01*
X1536203D01*
G01X1535317Y595583D02*
X1533797D01*
G01X1539340Y598000D02*
X1540860D01*
G01X1540100D02*
Y593000D01*
G01X1539340D02*
X1540860D01*
G01X1545200Y598000D02*
Y593000D01*
G01X1543743Y598000D02*
X1546657D01*
G01X1503642Y729449D02*
Y590473D01*
G01X1547736Y602283D02*
X1501082D01*
Y717638D01*
X1547736D01*
Y602283D01*
G01Y676496D02*
X1501082D01*
G01X1555983Y60500D02*
Y63600D01*
X1556903D01*
X1557210Y63445D01*
X1557440Y63083D01*
X1557517Y62670D01*
X1557440Y62257D01*
X1557248Y61947D01*
X1556903Y61792D01*
X1555983D01*
G01X1559083Y60500D02*
Y63600D01*
X1560042D01*
X1560348Y63445D01*
X1560540Y63238D01*
X1560617Y62825D01*
X1560540Y62412D01*
X1560310Y62153D01*
X1560042Y61998D01*
X1559083D01*
G01X1560042D02*
X1560617Y60500D01*
G01X1562950D02*
Y63600D01*
X1562490Y62980D01*
G01Y60500D02*
X1563410D01*
G01X1566050Y63600D02*
X1565743Y63497D01*
X1565513Y63238D01*
X1565360Y62928D01*
X1565245Y62515D01*
X1565207Y62050D01*
X1565245Y61585D01*
X1565360Y61172D01*
X1565513Y60862D01*
X1565743Y60603D01*
X1566050Y60500D01*
X1566357Y60603D01*
X1566587Y60862D01*
X1566740Y61172D01*
X1566855Y61585D01*
X1566893Y62050D01*
X1566855Y62515D01*
X1566740Y62928D01*
X1566587Y63238D01*
X1566357Y63497D01*
X1566050Y63600D01*
G01X1569150Y60500D02*
Y63600D01*
X1568690Y62980D01*
G01Y60500D02*
X1569610D01*
G01X1555483Y77500D02*
Y80600D01*
X1556403D01*
X1556710Y80445D01*
X1556940Y80083D01*
X1557017Y79670D01*
X1556940Y79257D01*
X1556748Y78947D01*
X1556403Y78792D01*
X1555483D01*
G01X1558583Y77500D02*
Y80600D01*
X1559542D01*
X1559848Y80445D01*
X1560040Y80238D01*
X1560117Y79825D01*
X1560040Y79412D01*
X1559810Y79153D01*
X1559542Y78998D01*
X1558583D01*
G01X1559542D02*
X1560117Y77500D01*
G01X1562450D02*
Y80600D01*
X1561990Y79980D01*
G01Y77500D02*
X1562910D01*
G01X1565550Y80600D02*
X1565243Y80497D01*
X1565013Y80238D01*
X1564860Y79928D01*
X1564745Y79515D01*
X1564707Y79050D01*
X1564745Y78585D01*
X1564860Y78172D01*
X1565013Y77862D01*
X1565243Y77603D01*
X1565550Y77500D01*
X1565857Y77603D01*
X1566087Y77862D01*
X1566240Y78172D01*
X1566355Y78585D01*
X1566393Y79050D01*
X1566355Y79515D01*
X1566240Y79928D01*
X1566087Y80238D01*
X1565857Y80497D01*
X1565550Y80600D01*
G01X1568650D02*
X1568343Y80497D01*
X1568113Y80238D01*
X1567960Y79928D01*
X1567845Y79515D01*
X1567807Y79050D01*
X1567845Y78585D01*
X1567960Y78172D01*
X1568113Y77862D01*
X1568343Y77603D01*
X1568650Y77500D01*
X1568957Y77603D01*
X1569187Y77862D01*
X1569340Y78172D01*
X1569455Y78585D01*
X1569493Y79050D01*
X1569455Y79515D01*
X1569340Y79928D01*
X1569187Y80238D01*
X1568957Y80497D01*
X1568650Y80600D01*
G01X1543000Y119000D02*
Y106000D01*
X1528000D01*
Y119000D01*
X1543000D01*
G01X1545983Y92500D02*
Y95600D01*
X1546903D01*
X1547210Y95445D01*
X1547440Y95083D01*
X1547517Y94670D01*
X1547440Y94257D01*
X1547248Y93947D01*
X1546903Y93792D01*
X1545983D01*
G01X1549850Y92500D02*
X1549543Y92552D01*
X1549275Y92758D01*
X1549045Y93068D01*
X1548892Y93430D01*
X1548815Y93843D01*
Y94257D01*
X1548892Y94670D01*
X1549045Y95032D01*
X1549275Y95342D01*
X1549543Y95548D01*
X1549850Y95600D01*
X1550157Y95548D01*
X1550425Y95342D01*
X1550655Y95032D01*
X1550808Y94670D01*
X1550885Y94257D01*
Y93843D01*
X1550808Y93430D01*
X1550655Y93068D01*
X1550425Y92758D01*
X1550157Y92552D01*
X1549850Y92500D01*
G01X1550157Y93327D02*
X1550617Y92500D01*
G01X1552950D02*
Y95600D01*
X1552490Y94980D01*
G01Y92500D02*
X1553410D01*
G01X1555207Y92965D02*
X1555437Y92707D01*
X1555705Y92552D01*
X1556050Y92500D01*
X1556395Y92603D01*
X1556663Y92810D01*
X1556855Y93172D01*
X1556893Y93585D01*
X1556817Y93998D01*
X1556625Y94257D01*
X1556357Y94463D01*
X1556088Y94515D01*
X1555820Y94463D01*
X1555475Y94257D01*
X1555590Y95600D01*
X1556625D01*
G01X1545815Y152148D02*
Y101889D01*
X1552400D01*
G01X1533883Y90500D02*
Y93600D01*
X1534803D01*
X1535110Y93445D01*
X1535340Y93083D01*
X1535417Y92670D01*
X1535340Y92257D01*
X1535148Y91947D01*
X1534803Y91792D01*
X1533883D01*
G01X1536907Y93600D02*
Y91378D01*
X1537060Y90913D01*
X1537367Y90603D01*
X1537750Y90500D01*
X1538133Y90603D01*
X1538440Y90913D01*
X1538593Y91378D01*
Y93600D01*
G01X1540007Y91120D02*
X1540237Y90758D01*
X1540543Y90552D01*
X1540888Y90500D01*
X1541195Y90552D01*
X1541502Y90810D01*
X1541693Y91120D01*
X1541732Y91430D01*
X1541655Y91792D01*
X1541387Y92050D01*
X1541118Y92153D01*
X1540773D01*
G01X1541118D02*
X1541348Y92308D01*
X1541540Y92567D01*
X1541617Y92877D01*
X1541540Y93187D01*
X1541348Y93445D01*
X1541003Y93600D01*
X1540658Y93548D01*
X1540313Y93342D01*
G01X1532743Y103831D02*
Y95169D01*
X1543257D01*
Y103831D01*
X1532743D01*
G01X1543250Y138799D02*
Y121201D01*
X1535950D01*
Y138799D01*
X1543250D01*
G01X1546733Y165000D02*
Y170000D01*
X1548253D01*
X1548760Y169750D01*
X1549140Y169167D01*
X1549267Y168500D01*
X1549140Y167833D01*
X1548823Y167333D01*
X1548253Y167083D01*
X1546733D01*
G01X1551707Y165750D02*
X1552087Y165333D01*
X1552530Y165083D01*
X1553100Y165000D01*
X1553670Y165167D01*
X1554113Y165500D01*
X1554430Y166083D01*
X1554493Y166750D01*
X1554367Y167417D01*
X1554050Y167833D01*
X1553607Y168167D01*
X1553163Y168250D01*
X1552720Y168167D01*
X1552150Y167833D01*
X1552340Y170000D01*
X1554050D01*
G01X1556997Y169167D02*
X1557377Y169667D01*
X1557820Y169917D01*
X1558327Y170000D01*
X1558960Y169833D01*
X1559403Y169417D01*
X1559530Y168917D01*
X1559467Y168417D01*
X1559213Y168000D01*
X1557947Y167167D01*
X1557377Y166583D01*
X1556997Y165750D01*
X1556870Y165000D01*
X1559530D01*
G01X1561717Y170000D02*
X1563300Y165000D01*
X1564883Y170000D01*
G01X1566500Y163333D02*
X1570300D01*
G01X1572170Y165000D02*
Y170000D01*
G01X1574830D02*
Y165000D01*
G01Y167500D02*
X1572170D01*
G01X1577270Y165667D02*
X1577777Y165250D01*
X1578347Y165000D01*
X1578853D01*
X1579360Y165250D01*
X1579740Y165667D01*
X1579930Y166250D01*
X1579803Y166833D01*
X1579487Y167333D01*
X1578917Y167667D01*
X1578157Y167833D01*
X1577713Y168167D01*
X1577523Y168750D01*
X1577650Y169333D01*
X1577967Y169750D01*
X1578410Y170000D01*
X1578853D01*
X1579297Y169833D01*
X1579677Y169417D01*
G01X1583700Y165000D02*
Y170000D01*
X1582940Y169000D01*
G01Y165000D02*
X1584460D01*
G01X1585185Y162125D02*
X1545815D01*
Y162048D01*
G01X1601917Y215236D02*
G03I-36417J0D01*
G01X1565500D02*
X1529068D01*
X1601917D01*
G01X1530983Y247000D02*
Y250100D01*
X1531903D01*
X1532210Y249945D01*
X1532440Y249583D01*
X1532517Y249170D01*
X1532440Y248757D01*
X1532248Y248447D01*
X1531903Y248292D01*
X1530983D01*
G01X1535693Y249842D02*
X1535463Y249997D01*
X1535195Y250100D01*
X1534888D01*
X1534543Y249945D01*
X1534275Y249687D01*
X1534083Y249377D01*
X1533930Y248860D01*
X1533892Y248395D01*
X1533968Y247930D01*
X1534083Y247620D01*
X1534313Y247310D01*
X1534582Y247103D01*
X1534850Y247000D01*
X1535118D01*
X1535387Y247103D01*
X1535617Y247258D01*
X1535808Y247465D01*
G01X1538410Y247000D02*
Y250100D01*
X1536992Y247878D01*
X1538908D01*
G01X1540207Y247620D02*
X1540437Y247258D01*
X1540743Y247052D01*
X1541088Y247000D01*
X1541395Y247052D01*
X1541702Y247310D01*
X1541893Y247620D01*
X1541932Y247930D01*
X1541855Y248292D01*
X1541587Y248550D01*
X1541318Y248653D01*
X1540973D01*
G01X1541318D02*
X1541548Y248808D01*
X1541740Y249067D01*
X1541817Y249377D01*
X1541740Y249687D01*
X1541548Y249945D01*
X1541203Y250100D01*
X1540858Y250048D01*
X1540513Y249842D01*
G01X1601917Y295236D02*
G03I-36417J0D01*
G01X1565500D02*
X1529068D01*
X1601917D01*
G01X1531983Y327500D02*
Y330600D01*
X1532903D01*
X1533210Y330445D01*
X1533440Y330083D01*
X1533517Y329670D01*
X1533440Y329257D01*
X1533248Y328947D01*
X1532903Y328792D01*
X1531983D01*
G01X1536693Y330342D02*
X1536463Y330497D01*
X1536195Y330600D01*
X1535888D01*
X1535543Y330445D01*
X1535275Y330187D01*
X1535083Y329877D01*
X1534930Y329360D01*
X1534892Y328895D01*
X1534968Y328430D01*
X1535083Y328120D01*
X1535313Y327810D01*
X1535582Y327603D01*
X1535850Y327500D01*
X1536118D01*
X1536387Y327603D01*
X1536617Y327758D01*
X1536808Y327965D01*
G01X1539410Y327500D02*
Y330600D01*
X1537992Y328378D01*
X1539908D01*
G01X1542050Y327500D02*
Y330600D01*
X1541590Y329980D01*
G01Y327500D02*
X1542510D01*
G01X1601917Y375236D02*
G03I-36417J0D01*
G01X1565500D02*
X1529068D01*
X1601917D01*
G01X1533983Y407500D02*
Y410600D01*
X1534903D01*
X1535210Y410445D01*
X1535440Y410083D01*
X1535517Y409670D01*
X1535440Y409257D01*
X1535248Y408947D01*
X1534903Y408792D01*
X1533983D01*
G01X1538693Y410342D02*
X1538463Y410497D01*
X1538195Y410600D01*
X1537888D01*
X1537543Y410445D01*
X1537275Y410187D01*
X1537083Y409877D01*
X1536930Y409360D01*
X1536892Y408895D01*
X1536968Y408430D01*
X1537083Y408120D01*
X1537313Y407810D01*
X1537582Y407603D01*
X1537850Y407500D01*
X1538118D01*
X1538387Y407603D01*
X1538617Y407758D01*
X1538808Y407965D01*
G01X1540107Y408120D02*
X1540337Y407758D01*
X1540643Y407552D01*
X1540988Y407500D01*
X1541295Y407552D01*
X1541602Y407810D01*
X1541793Y408120D01*
X1541832Y408430D01*
X1541755Y408792D01*
X1541487Y409050D01*
X1541218Y409153D01*
X1540873D01*
G01X1541218D02*
X1541448Y409308D01*
X1541640Y409567D01*
X1541717Y409877D01*
X1541640Y410187D01*
X1541448Y410445D01*
X1541103Y410600D01*
X1540758Y410548D01*
X1540413Y410342D01*
G01X1543207Y408120D02*
X1543437Y407758D01*
X1543743Y407552D01*
X1544088Y407500D01*
X1544395Y407552D01*
X1544702Y407810D01*
X1544893Y408120D01*
X1544932Y408430D01*
X1544855Y408792D01*
X1544587Y409050D01*
X1544318Y409153D01*
X1543973D01*
G01X1544318D02*
X1544548Y409308D01*
X1544740Y409567D01*
X1544817Y409877D01*
X1544740Y410187D01*
X1544548Y410445D01*
X1544203Y410600D01*
X1543858Y410548D01*
X1543513Y410342D01*
G01X1601917Y455236D02*
G03I-36417J0D01*
G01X1565500D02*
X1529068D01*
X1601917D01*
G01X1533483Y487000D02*
Y490100D01*
X1534403D01*
X1534710Y489945D01*
X1534940Y489583D01*
X1535017Y489170D01*
X1534940Y488757D01*
X1534748Y488447D01*
X1534403Y488292D01*
X1533483D01*
G01X1538193Y489842D02*
X1537963Y489997D01*
X1537695Y490100D01*
X1537388D01*
X1537043Y489945D01*
X1536775Y489687D01*
X1536583Y489377D01*
X1536430Y488860D01*
X1536392Y488395D01*
X1536468Y487930D01*
X1536583Y487620D01*
X1536813Y487310D01*
X1537082Y487103D01*
X1537350Y487000D01*
X1537618D01*
X1537887Y487103D01*
X1538117Y487258D01*
X1538308Y487465D01*
G01X1539607Y487620D02*
X1539837Y487258D01*
X1540143Y487052D01*
X1540488Y487000D01*
X1540795Y487052D01*
X1541102Y487310D01*
X1541293Y487620D01*
X1541332Y487930D01*
X1541255Y488292D01*
X1540987Y488550D01*
X1540718Y488653D01*
X1540373D01*
G01X1540718D02*
X1540948Y488808D01*
X1541140Y489067D01*
X1541217Y489377D01*
X1541140Y489687D01*
X1540948Y489945D01*
X1540603Y490100D01*
X1540258Y490048D01*
X1539913Y489842D01*
G01X1543550Y487000D02*
Y490100D01*
X1543090Y489480D01*
G01Y487000D02*
X1544010D01*
G01X1601917Y535236D02*
G03I-36417J0D01*
G01X1565500D02*
X1529068D01*
X1601917D01*
G01X1535983Y569500D02*
Y572600D01*
X1536903D01*
X1537210Y572445D01*
X1537440Y572083D01*
X1537517Y571670D01*
X1537440Y571257D01*
X1537248Y570947D01*
X1536903Y570792D01*
X1535983D01*
G01X1540693Y572342D02*
X1540463Y572497D01*
X1540195Y572600D01*
X1539888D01*
X1539543Y572445D01*
X1539275Y572187D01*
X1539083Y571877D01*
X1538930Y571360D01*
X1538892Y570895D01*
X1538968Y570430D01*
X1539083Y570120D01*
X1539313Y569810D01*
X1539582Y569603D01*
X1539850Y569500D01*
X1540118D01*
X1540387Y569603D01*
X1540617Y569758D01*
X1540808Y569965D01*
G01X1542222Y572083D02*
X1542452Y572393D01*
X1542720Y572548D01*
X1543027Y572600D01*
X1543410Y572497D01*
X1543678Y572238D01*
X1543755Y571928D01*
X1543717Y571618D01*
X1543563Y571360D01*
X1542797Y570843D01*
X1542452Y570482D01*
X1542222Y569965D01*
X1542145Y569500D01*
X1543755D01*
G01X1545398Y569862D02*
X1545667Y569603D01*
X1545973Y569500D01*
X1546280Y569603D01*
X1546548Y569913D01*
X1546740Y570378D01*
X1546817Y570843D01*
Y571412D01*
X1546740Y571877D01*
X1546548Y572290D01*
X1546318Y572497D01*
X1546050Y572600D01*
X1545743Y572497D01*
X1545513Y572290D01*
X1545360Y571980D01*
X1545283Y571567D01*
X1545360Y571205D01*
X1545552Y570843D01*
X1545782Y570637D01*
X1546050Y570585D01*
X1546357Y570688D01*
X1546587Y570947D01*
X1546817Y571412D01*
G01X1555119Y726496D02*
X1608268D01*
Y593819D01*
X1555119D01*
Y726496D01*
G01X1543308Y738307D02*
X1620079D01*
Y582008D01*
X1543308D01*
Y738307D01*
G01X1555119Y690276D02*
X1608268D01*
G01X1599780Y74400D02*
X1571220D01*
Y59600D01*
X1599780D01*
Y74400D01*
G01Y92400D02*
X1571220D01*
Y77600D01*
X1599780D01*
Y92400D01*
G01X1558600Y101889D02*
X1572400D01*
G01X1578600D02*
X1585185D01*
Y152148D01*
G01Y162048D02*
Y162125D01*
G01X1559547Y729449D02*
Y590473D01*
G01X1565633Y585000D02*
Y590000D01*
X1567153D01*
X1567660Y589750D01*
X1568040Y589167D01*
X1568167Y588500D01*
X1568040Y587833D01*
X1567723Y587333D01*
X1567153Y587083D01*
X1565633D01*
G01X1570733Y585000D02*
Y590000D01*
X1572317D01*
X1572823Y589750D01*
X1573140Y589417D01*
X1573267Y588750D01*
X1573140Y588083D01*
X1572760Y587667D01*
X1572317Y587417D01*
X1570733D01*
G01X1572317D02*
X1573267Y585000D01*
G01X1578367D02*
X1575833D01*
Y590000D01*
X1578367D01*
G01X1577353Y587583D02*
X1575833D01*
G01X1580870Y585667D02*
X1581377Y585250D01*
X1581947Y585000D01*
X1582453D01*
X1582960Y585250D01*
X1583340Y585667D01*
X1583530Y586250D01*
X1583403Y586833D01*
X1583087Y587333D01*
X1582517Y587667D01*
X1581757Y587833D01*
X1581313Y588167D01*
X1581123Y588750D01*
X1581250Y589333D01*
X1581567Y589750D01*
X1582010Y590000D01*
X1582453D01*
X1582897Y589833D01*
X1583277Y589417D01*
G01X1585970Y585667D02*
X1586477Y585250D01*
X1587047Y585000D01*
X1587553D01*
X1588060Y585250D01*
X1588440Y585667D01*
X1588630Y586250D01*
X1588503Y586833D01*
X1588187Y587333D01*
X1587617Y587667D01*
X1586857Y587833D01*
X1586413Y588167D01*
X1586223Y588750D01*
X1586350Y589333D01*
X1586667Y589750D01*
X1587110Y590000D01*
X1587553D01*
X1587997Y589833D01*
X1588377Y589417D01*
G01X1591577Y586667D02*
X1593223D01*
G01X1596297Y585000D02*
Y590000D01*
X1598703D01*
G01X1597817Y587583D02*
X1596297D01*
G01X1601840Y590000D02*
X1603360D01*
G01X1602600D02*
Y585000D01*
G01X1601840D02*
X1603360D01*
G01X1607700Y590000D02*
Y585000D01*
G01X1606243Y590000D02*
X1609157D01*
G01X1580133Y577620D02*
X1580325Y577310D01*
X1580555Y577103D01*
X1580823Y577000D01*
X1581130Y577103D01*
X1581360Y577310D01*
X1581590Y577620D01*
X1581667Y578033D01*
Y580100D01*
G01X1583233Y577000D02*
Y580100D01*
X1584153D01*
X1584460Y579945D01*
X1584690Y579583D01*
X1584767Y579170D01*
X1584690Y578757D01*
X1584498Y578447D01*
X1584153Y578292D01*
X1583233D01*
G01X1587100Y577000D02*
Y580100D01*
X1586640Y579480D01*
G01Y577000D02*
X1587560D01*
G01X1612073Y79700D02*
X1614313D01*
G01X1613100Y81325D02*
Y78075D01*
G01X1596907Y108500D02*
Y111600D01*
X1597673D01*
X1597980Y111445D01*
X1598210Y111238D01*
X1598402Y110928D01*
X1598555Y110567D01*
X1598593Y110050D01*
X1598555Y109533D01*
X1598402Y109172D01*
X1598210Y108862D01*
X1597980Y108655D01*
X1597673Y108500D01*
X1596907D01*
G01X1600850D02*
Y111600D01*
X1600390Y110980D01*
G01Y108500D02*
X1601310D01*
G01X1602020Y113100D02*
X1594930D01*
Y116900D01*
X1602020D01*
G01X1602620Y113100D02*
X1595430D01*
Y116900D01*
X1602620D01*
G01X1603020Y113100D02*
X1595930D01*
Y116900D01*
X1603070D01*
Y113150D01*
G01X1607799Y145350D02*
X1590201D01*
Y152650D01*
X1607799D01*
Y145350D01*
G01X1590201Y143650D02*
X1607799D01*
Y136350D01*
X1590201D01*
Y143650D01*
G01X1607799Y127350D02*
X1590201D01*
Y134650D01*
X1607799D01*
Y127350D01*
G01X1590201Y125650D02*
X1607799D01*
Y118350D01*
X1590201D01*
Y125650D01*
G01Y161650D02*
X1607799D01*
Y154350D01*
X1590201D01*
Y161650D01*
G01X1610900Y174600D02*
X1617100D01*
Y171400D01*
X1610900D01*
Y174600D01*
G01Y171100D02*
X1617100D01*
Y167900D01*
X1610900D01*
Y171100D01*
G01Y167100D02*
X1617100D01*
Y163900D01*
X1610900D01*
Y167100D01*
G01X1620100Y187100D02*
Y180900D01*
X1616900D01*
Y187100D01*
X1620100D01*
G01X1620107Y87450D02*
Y90550D01*
X1620873D01*
X1621180Y90395D01*
X1621410Y90188D01*
X1621602Y89878D01*
X1621755Y89517D01*
X1621793Y89000D01*
X1621755Y88483D01*
X1621602Y88122D01*
X1621410Y87812D01*
X1621180Y87605D01*
X1620873Y87450D01*
X1620107D01*
G01X1623207Y87915D02*
X1623437Y87657D01*
X1623705Y87502D01*
X1624050Y87450D01*
X1624395Y87553D01*
X1624663Y87760D01*
X1624855Y88122D01*
X1624893Y88535D01*
X1624817Y88948D01*
X1624625Y89207D01*
X1624357Y89413D01*
X1624088Y89465D01*
X1623820Y89413D01*
X1623475Y89207D01*
X1623590Y90550D01*
X1624625D01*
G01X1649473Y74052D02*
X1619914D01*
Y85548D01*
X1649473D01*
Y74052D01*
G01X1627360Y106557D02*
Y112757D01*
X1630560D01*
Y106557D01*
X1627360D01*
G01X1629370Y117540D02*
X1623170D01*
Y120740D01*
X1629370D01*
Y117540D01*
G01X1623170Y116740D02*
X1629370D01*
Y113540D01*
X1623170D01*
Y116740D01*
G01X1619360Y106557D02*
Y112757D01*
X1622560D01*
Y106557D01*
X1619360D01*
G01X1623340D02*
Y112757D01*
X1626540D01*
Y106557D01*
X1623340D01*
G01X1639870Y89340D02*
X1633670D01*
Y92540D01*
X1639870D01*
Y89340D01*
G01X1626760Y103330D02*
X1636960D01*
Y98730D01*
X1626760D01*
Y103330D01*
G01Y98230D02*
X1636960D01*
Y93630D01*
X1626760D01*
Y98230D01*
G01X1640500Y99850D02*
Y97350D01*
X1640820Y97850D01*
G01Y99850D02*
X1640180D01*
G01X1638807Y97767D02*
X1638647Y97517D01*
X1638460Y97392D01*
X1638247Y97350D01*
X1637980Y97433D01*
X1637793Y97642D01*
X1637740Y97892D01*
X1637767Y98142D01*
X1637873Y98350D01*
X1638407Y98767D01*
X1638647Y99058D01*
X1638807Y99475D01*
X1638860Y99850D01*
X1637740D01*
G01X1619650Y105400D02*
X1622150D01*
X1621650Y105720D01*
G01X1619650D02*
Y105080D01*
G01Y103200D02*
X1622150D01*
X1621650Y103520D01*
G01X1619650D02*
Y102880D01*
G01X1629967Y119900D02*
X1632467D01*
X1631967Y120220D01*
G01X1629967D02*
Y119580D01*
G01X1632467Y117700D02*
X1632384Y117913D01*
X1632175Y118073D01*
X1631925Y118180D01*
X1631592Y118260D01*
X1631217Y118287D01*
X1630842Y118260D01*
X1630509Y118180D01*
X1630259Y118073D01*
X1630050Y117913D01*
X1629967Y117700D01*
X1630050Y117487D01*
X1630259Y117327D01*
X1630509Y117220D01*
X1630842Y117140D01*
X1631217Y117113D01*
X1631592Y117140D01*
X1631925Y117220D01*
X1632175Y117327D01*
X1632384Y117487D01*
X1632467Y117700D01*
G01X1633861Y110232D02*
Y107098D01*
X1635026D01*
G01X1633861Y114168D02*
Y112232D01*
G01X1635026Y119302D02*
X1633861D01*
Y116168D01*
G01X1638557Y149550D02*
Y147328D01*
X1638710Y146863D01*
X1639017Y146553D01*
X1639400Y146450D01*
X1639783Y146553D01*
X1640090Y146863D01*
X1640243Y147328D01*
Y149550D01*
G01X1641657Y147070D02*
X1641887Y146708D01*
X1642193Y146502D01*
X1642538Y146450D01*
X1642845Y146502D01*
X1643152Y146760D01*
X1643343Y147070D01*
X1643382Y147380D01*
X1643305Y147742D01*
X1643037Y148000D01*
X1642768Y148103D01*
X1642423D01*
G01X1642768D02*
X1642998Y148258D01*
X1643190Y148517D01*
X1643267Y148827D01*
X1643190Y149137D01*
X1642998Y149395D01*
X1642653Y149550D01*
X1642308Y149498D01*
X1641963Y149292D01*
G01X1645600Y149550D02*
X1645293Y149447D01*
X1645063Y149188D01*
X1644910Y148878D01*
X1644795Y148465D01*
X1644757Y148000D01*
X1644795Y147535D01*
X1644910Y147122D01*
X1645063Y146812D01*
X1645293Y146553D01*
X1645600Y146450D01*
X1645907Y146553D01*
X1646137Y146812D01*
X1646290Y147122D01*
X1646405Y147535D01*
X1646443Y148000D01*
X1646405Y148465D01*
X1646290Y148878D01*
X1646137Y149188D01*
X1645907Y149447D01*
X1645600Y149550D01*
G01X1625694Y159312D02*
X1637506D01*
Y146688D01*
X1625694D01*
Y159312D01*
G01X1630500Y143600D02*
X1636700D01*
Y140400D01*
X1630500D01*
Y143600D01*
G01X1623700Y153600D02*
Y147400D01*
X1620500D01*
Y153600D01*
X1623700D01*
G01X1626170Y125840D02*
Y132040D01*
X1629370D01*
Y125840D01*
X1626170D01*
G01X1643680Y125900D02*
Y132100D01*
X1646880D01*
Y125900D01*
X1643680D01*
G01X1637170Y125840D02*
Y132040D01*
X1640370D01*
Y125840D01*
X1637170D01*
G01X1647670D02*
Y132040D01*
X1650870D01*
Y125840D01*
X1647670D01*
G01X1630170D02*
Y132040D01*
X1633370D01*
Y125840D01*
X1630170D01*
G01X1634153Y123241D02*
X1633967Y123450D01*
X1633753Y123533D01*
X1633540Y123450D01*
X1633353Y123200D01*
X1633220Y122825D01*
X1633167Y122450D01*
Y121991D01*
X1633220Y121616D01*
X1633353Y121283D01*
X1633513Y121116D01*
X1633700Y121033D01*
X1633913Y121116D01*
X1634073Y121283D01*
X1634180Y121533D01*
X1634233Y121866D01*
X1634180Y122158D01*
X1634047Y122450D01*
X1633887Y122616D01*
X1633700Y122658D01*
X1633487Y122575D01*
X1633327Y122366D01*
X1633167Y121991D01*
G01X1662900Y182600D02*
Y151400D01*
X1647100D01*
Y182600D01*
X1652700D01*
X1655000Y180300D01*
X1657300Y182600D01*
X1662900D01*
G01X1631100Y176400D02*
X1624900D01*
Y179600D01*
X1631100D01*
Y176400D01*
G01Y170900D02*
X1624900D01*
Y174100D01*
X1631100D01*
Y170900D01*
G01X1633100Y165900D02*
X1626900D01*
Y169100D01*
X1633100D01*
Y165900D01*
G01Y161900D02*
X1626900D01*
Y165100D01*
X1633100D01*
Y161900D01*
G01X1647807Y187600D02*
Y185378D01*
X1647960Y184913D01*
X1648267Y184603D01*
X1648650Y184500D01*
X1649033Y184603D01*
X1649340Y184913D01*
X1649493Y185378D01*
Y187600D01*
G01X1651750Y184500D02*
X1652018Y184552D01*
X1652325Y184707D01*
X1652517Y184965D01*
X1652593Y185327D01*
X1652517Y185688D01*
X1652287Y185998D01*
X1651942Y186153D01*
X1651558D01*
X1651328Y186257D01*
X1651137Y186515D01*
X1651060Y186877D01*
X1651175Y187238D01*
X1651443Y187497D01*
X1651750Y187600D01*
X1652057Y187497D01*
X1652325Y187238D01*
X1652440Y186877D01*
X1652363Y186515D01*
X1652172Y186257D01*
X1651942Y186153D01*
X1651558D01*
X1651213Y185998D01*
X1650983Y185688D01*
X1650907Y185327D01*
X1650983Y184965D01*
X1651175Y184707D01*
X1651482Y184552D01*
X1651750Y184500D01*
G01X1618600Y199200D02*
Y205800D01*
X1631600D01*
Y199200D01*
X1618600D01*
G01X1634450Y204057D02*
X1636672D01*
X1637137Y204210D01*
X1637447Y204517D01*
X1637550Y204900D01*
X1637447Y205283D01*
X1637137Y205590D01*
X1636672Y205743D01*
X1634450D01*
G01X1634967Y207272D02*
X1634657Y207502D01*
X1634502Y207770D01*
X1634450Y208077D01*
X1634553Y208460D01*
X1634812Y208728D01*
X1635122Y208805D01*
X1635432Y208767D01*
X1635690Y208613D01*
X1636207Y207847D01*
X1636568Y207502D01*
X1637085Y207272D01*
X1637550Y207195D01*
Y208805D01*
G01X1637188Y210448D02*
X1637447Y210717D01*
X1637550Y211023D01*
X1637447Y211330D01*
X1637137Y211598D01*
X1636672Y211790D01*
X1636207Y211867D01*
X1635638D01*
X1635173Y211790D01*
X1634760Y211598D01*
X1634553Y211368D01*
X1634450Y211100D01*
X1634553Y210793D01*
X1634760Y210563D01*
X1635070Y210410D01*
X1635483Y210333D01*
X1635845Y210410D01*
X1636207Y210602D01*
X1636413Y210832D01*
X1636465Y211100D01*
X1636362Y211407D01*
X1636103Y211637D01*
X1635638Y211867D01*
G01X1645412Y196906D02*
Y185094D01*
X1632788D01*
Y196906D01*
X1645412D01*
G01X1624900Y184600D02*
X1631100D01*
Y181400D01*
X1624900D01*
Y184600D01*
G01X1639400Y199900D02*
Y206100D01*
X1642600D01*
Y199900D01*
X1639400D01*
G01X1628000Y190900D02*
Y197100D01*
X1631200D01*
Y190900D01*
X1628000D01*
G01X1704724Y236614D02*
G03X1643261Y226920I-31496J0D01*
G01X1704724Y411614D02*
G03I-31496J0D01*
G01X1653013Y79500D02*
X1650587D01*
G01X1658107Y105167D02*
X1657947Y104917D01*
X1657760Y104792D01*
X1657547Y104750D01*
X1657280Y104833D01*
X1657093Y105042D01*
X1657040Y105292D01*
X1657067Y105542D01*
X1657173Y105750D01*
X1657707Y106167D01*
X1657947Y106458D01*
X1658107Y106875D01*
X1658160Y107250D01*
X1657040D01*
G01X1655400Y104750D02*
X1655613Y104833D01*
X1655773Y105042D01*
X1655880Y105292D01*
X1655960Y105625D01*
X1655987Y106000D01*
X1655960Y106375D01*
X1655880Y106708D01*
X1655773Y106958D01*
X1655613Y107167D01*
X1655400Y107250D01*
X1655187Y107167D01*
X1655027Y106958D01*
X1654920Y106708D01*
X1654840Y106375D01*
X1654813Y106000D01*
X1654840Y105625D01*
X1654920Y105292D01*
X1655027Y105042D01*
X1655187Y104833D01*
X1655400Y104750D01*
G01X1658250Y118407D02*
X1658500Y118247D01*
X1658625Y118060D01*
X1658667Y117847D01*
X1658584Y117580D01*
X1658375Y117393D01*
X1658125Y117340D01*
X1657875Y117367D01*
X1657667Y117473D01*
X1657250Y118007D01*
X1656959Y118247D01*
X1656542Y118407D01*
X1656167Y118460D01*
Y117340D01*
G01Y115700D02*
X1658667D01*
X1658167Y116020D01*
G01X1656167D02*
Y115380D01*
G01X1655334Y114300D02*
Y112700D01*
G01X1658250Y111807D02*
X1658500Y111647D01*
X1658625Y111460D01*
X1658667Y111247D01*
X1658584Y110980D01*
X1658375Y110793D01*
X1658125Y110740D01*
X1657875Y110767D01*
X1657667Y110873D01*
X1657250Y111407D01*
X1656959Y111647D01*
X1656542Y111807D01*
X1656167Y111860D01*
Y110740D01*
G01X1658250Y109607D02*
X1658500Y109447D01*
X1658625Y109260D01*
X1658667Y109047D01*
X1658584Y108780D01*
X1658375Y108593D01*
X1658125Y108540D01*
X1657875Y108567D01*
X1657667Y108673D01*
X1657250Y109207D01*
X1656959Y109447D01*
X1656542Y109607D01*
X1656167Y109660D01*
Y108540D01*
G01X1653939Y112250D02*
Y114150D01*
G01X1652774Y107098D02*
X1653939D01*
G01Y116161D02*
Y119302D01*
X1652766D01*
G01X1653939Y107098D02*
Y110239D01*
G01X1663633Y90707D02*
X1660533D01*
Y91473D01*
X1660688Y91780D01*
X1660895Y92010D01*
X1661205Y92202D01*
X1661566Y92355D01*
X1662083Y92393D01*
X1662600Y92355D01*
X1662961Y92202D01*
X1663271Y92010D01*
X1663478Y91780D01*
X1663633Y91473D01*
Y90707D01*
G01Y95110D02*
X1660533D01*
X1662755Y93692D01*
Y95608D01*
G01X1680756Y90604D02*
Y121696D01*
X1665244D01*
Y90604D01*
X1680756D01*
G01X1649940Y103980D02*
X1656140D01*
Y100780D01*
X1649940D01*
Y103980D01*
G01X1663600Y113100D02*
Y106900D01*
X1660400D01*
Y113100D01*
X1663600D01*
G01X1654870Y132040D02*
Y125840D01*
X1651670D01*
Y132040D01*
X1654870D01*
G01X1658950Y120557D02*
X1661172D01*
X1661637Y120710D01*
X1661947Y121017D01*
X1662050Y121400D01*
X1661947Y121783D01*
X1661637Y122090D01*
X1661172Y122243D01*
X1658950D01*
G01X1661430Y123657D02*
X1661792Y123887D01*
X1661998Y124193D01*
X1662050Y124538D01*
X1661998Y124845D01*
X1661740Y125152D01*
X1661430Y125343D01*
X1661120Y125382D01*
X1660758Y125305D01*
X1660500Y125037D01*
X1660397Y124768D01*
Y124423D01*
G01Y124768D02*
X1660242Y124998D01*
X1659983Y125190D01*
X1659673Y125267D01*
X1659363Y125190D01*
X1659105Y124998D01*
X1658950Y124653D01*
X1659002Y124308D01*
X1659208Y123963D01*
G01X1662050Y127600D02*
X1661998Y127868D01*
X1661843Y128175D01*
X1661585Y128367D01*
X1661223Y128443D01*
X1660862Y128367D01*
X1660552Y128137D01*
X1660397Y127792D01*
Y127408D01*
X1660293Y127178D01*
X1660035Y126987D01*
X1659673Y126910D01*
X1659312Y127025D01*
X1659053Y127293D01*
X1658950Y127600D01*
X1659053Y127907D01*
X1659312Y128175D01*
X1659673Y128290D01*
X1660035Y128213D01*
X1660293Y128022D01*
X1660397Y127792D01*
Y127408D01*
X1660552Y127063D01*
X1660862Y126833D01*
X1661223Y126757D01*
X1661585Y126833D01*
X1661843Y127025D01*
X1661998Y127332D01*
X1662050Y127600D01*
G01X1647874Y217928D02*
G03X1704724Y236614I25354J18686D01*
G01X1650900Y200600D02*
X1657100D01*
Y197400D01*
X1650900D01*
Y200600D01*
G01X1663400Y188100D02*
X1669600D01*
Y184900D01*
X1663400D01*
Y188100D01*
G01X1669445Y270500D02*
Y273600D01*
G01X1671055D02*
Y270500D01*
G01Y272050D02*
X1669445D01*
G01X1672622Y273083D02*
X1672852Y273393D01*
X1673120Y273548D01*
X1673427Y273600D01*
X1673810Y273497D01*
X1674078Y273238D01*
X1674155Y272928D01*
X1674117Y272618D01*
X1673963Y272360D01*
X1673197Y271843D01*
X1672852Y271482D01*
X1672622Y270965D01*
X1672545Y270500D01*
X1674155D01*
G01X1676910D02*
Y273600D01*
X1675492Y271378D01*
X1677408D01*
G01X1670445Y375500D02*
Y378600D01*
G01X1672055D02*
Y375500D01*
G01Y377050D02*
X1670445D01*
G01X1673622Y378083D02*
X1673852Y378393D01*
X1674120Y378548D01*
X1674427Y378600D01*
X1674810Y378497D01*
X1675078Y378238D01*
X1675155Y377928D01*
X1675117Y377618D01*
X1674963Y377360D01*
X1674197Y376843D01*
X1673852Y376482D01*
X1673622Y375965D01*
X1673545Y375500D01*
X1675155D01*
G01X1676607Y376120D02*
X1676837Y375758D01*
X1677143Y375552D01*
X1677488Y375500D01*
X1677795Y375552D01*
X1678102Y375810D01*
X1678293Y376120D01*
X1678332Y376430D01*
X1678255Y376792D01*
X1677987Y377050D01*
X1677718Y377153D01*
X1677373D01*
G01X1677718D02*
X1677948Y377308D01*
X1678140Y377567D01*
X1678217Y377877D01*
X1678140Y378187D01*
X1677948Y378445D01*
X1677603Y378600D01*
X1677258Y378548D01*
X1676913Y378342D01*
G01X1677595Y473950D02*
Y477050D01*
G01X1679205D02*
Y473950D01*
G01Y475500D02*
X1677595D01*
G01X1680657Y474570D02*
X1680887Y474208D01*
X1681193Y474002D01*
X1681538Y473950D01*
X1681845Y474002D01*
X1682152Y474260D01*
X1682343Y474570D01*
X1682382Y474880D01*
X1682305Y475242D01*
X1682037Y475500D01*
X1681768Y475603D01*
X1681423D01*
G01X1681768D02*
X1681998Y475758D01*
X1682190Y476017D01*
X1682267Y476327D01*
X1682190Y476637D01*
X1681998Y476895D01*
X1681653Y477050D01*
X1681308Y476998D01*
X1680963Y476792D01*
G01X1684523Y473950D02*
X1684600Y474622D01*
X1684715Y475190D01*
X1684868Y475707D01*
X1685060Y476275D01*
X1685367Y477050D01*
X1683833D01*
G01X1680845Y58000D02*
Y61100D01*
G01X1682455D02*
Y58000D01*
G01Y59550D02*
X1680845D01*
G01X1684750Y58000D02*
Y61100D01*
X1684290Y60480D01*
G01Y58000D02*
X1685210D01*
G01X1688310D02*
Y61100D01*
X1686892Y58878D01*
X1688808D01*
G01X1684000Y97807D02*
X1686222D01*
X1686687Y97960D01*
X1686997Y98267D01*
X1687100Y98650D01*
X1686997Y99033D01*
X1686687Y99340D01*
X1686222Y99493D01*
X1684000D01*
G01X1686738Y101098D02*
X1686997Y101367D01*
X1687100Y101673D01*
X1686997Y101980D01*
X1686687Y102248D01*
X1686222Y102440D01*
X1685757Y102517D01*
X1685188D01*
X1684723Y102440D01*
X1684310Y102248D01*
X1684103Y102018D01*
X1684000Y101750D01*
X1684103Y101443D01*
X1684310Y101213D01*
X1684620Y101060D01*
X1685033Y100983D01*
X1685395Y101060D01*
X1685757Y101252D01*
X1685963Y101482D01*
X1686015Y101750D01*
X1685912Y102057D01*
X1685653Y102287D01*
X1685188Y102517D01*
G01X1688700Y102500D02*
Y98700D01*
X1690500Y96900D01*
X1688700Y95100D01*
Y91300D01*
X1708500D01*
Y102500D01*
X1688700D01*
G01X1688500Y131300D02*
Y137500D01*
X1691700D01*
Y131300D01*
X1688500D01*
G01X1709600Y132900D02*
X1703400D01*
Y136100D01*
X1709600D01*
Y132900D01*
G01Y127900D02*
X1703400D01*
Y131100D01*
X1709600D01*
Y127900D01*
G01X1698500Y120300D02*
Y126500D01*
X1701700D01*
Y120300D01*
X1698500D01*
G01X1691700Y126500D02*
Y120300D01*
X1688500D01*
Y126500D01*
X1691700D01*
G01X1678900Y149600D02*
X1685100D01*
Y146400D01*
X1678900D01*
Y149600D01*
G01X1697100Y146400D02*
X1690900D01*
Y149600D01*
X1697100D01*
Y146400D01*
G01X1686700Y126500D02*
Y120300D01*
X1683500D01*
Y126500D01*
X1686700D01*
G01X1678900Y177100D02*
X1685100D01*
Y173900D01*
X1678900D01*
Y177100D01*
G01X1697100Y162900D02*
X1690900D01*
Y166100D01*
X1697100D01*
Y162900D01*
G01Y168400D02*
X1690900D01*
Y171600D01*
X1697100D01*
Y168400D01*
G01Y173900D02*
X1690900D01*
Y177100D01*
X1697100D01*
Y173900D01*
G01X1678900Y155100D02*
X1685100D01*
Y151900D01*
X1678900D01*
Y155100D01*
G01Y160600D02*
X1685100D01*
Y157400D01*
X1678900D01*
Y160600D01*
G01X1697100Y151900D02*
X1690900D01*
Y155100D01*
X1697100D01*
Y151900D01*
G01Y157400D02*
X1690900D01*
Y160600D01*
X1697100D01*
Y157400D01*
G01X1678900Y166100D02*
X1685100D01*
Y162900D01*
X1678900D01*
Y166100D01*
G01Y171600D02*
X1685100D01*
Y168400D01*
X1678900D01*
Y171600D01*
G01X1705600Y158900D02*
Y165100D01*
X1708800D01*
Y158900D01*
X1705600D01*
G01X1697100Y184900D02*
X1690900D01*
Y188100D01*
X1697100D01*
Y184900D01*
G01X1685100D02*
X1678900D01*
Y188100D01*
X1685100D01*
Y184900D01*
G01X1678900Y182600D02*
X1685100D01*
Y179400D01*
X1678900D01*
Y182600D01*
G01X1697100Y179400D02*
X1690900D01*
Y182600D01*
X1697100D01*
Y179400D01*
G01X1701400Y209600D02*
X1707600D01*
Y206400D01*
X1701400D01*
Y209600D01*
G01X1709100Y200100D02*
Y193900D01*
X1705900D01*
Y200100D01*
X1709100D01*
G01X1707233Y216500D02*
Y224000D01*
X1709473D01*
X1710220Y223625D01*
X1710780Y222750D01*
X1710967Y221750D01*
X1710780Y220750D01*
X1710313Y220000D01*
X1709473Y219625D01*
X1707233D01*
G01X1714547Y218000D02*
X1715107Y217125D01*
X1715853Y216625D01*
X1716693Y216500D01*
X1717440Y216625D01*
X1718187Y217250D01*
X1718653Y218000D01*
X1718747Y218750D01*
X1718560Y219625D01*
X1717907Y220250D01*
X1717253Y220500D01*
X1716413D01*
G01X1717253D02*
X1717813Y220875D01*
X1718280Y221500D01*
X1718467Y222250D01*
X1718280Y223000D01*
X1717813Y223625D01*
X1716973Y224000D01*
X1716133Y223875D01*
X1715293Y223375D01*
G01X1721767Y224000D02*
X1724100Y216500D01*
X1726433Y224000D01*
G01X1729547Y218000D02*
X1730107Y217125D01*
X1730853Y216625D01*
X1731693Y216500D01*
X1732440Y216625D01*
X1733187Y217250D01*
X1733653Y218000D01*
X1733747Y218750D01*
X1733560Y219625D01*
X1732907Y220250D01*
X1732253Y220500D01*
X1731413D01*
G01X1732253D02*
X1732813Y220875D01*
X1733280Y221500D01*
X1733467Y222250D01*
X1733280Y223000D01*
X1732813Y223625D01*
X1731973Y224000D01*
X1731133Y223875D01*
X1730293Y223375D01*
G01X1744267Y216500D02*
X1746600Y224000D01*
X1748933Y216500D01*
G01X1748093Y219125D02*
X1745107D01*
G01X1752047Y224000D02*
Y218625D01*
X1752420Y217500D01*
X1753167Y216750D01*
X1754100Y216500D01*
X1755033Y216750D01*
X1755780Y217500D01*
X1756153Y218625D01*
Y224000D01*
G01X1759640Y216500D02*
X1763560Y224000D01*
G01X1759640D02*
X1763560Y216500D01*
G01X1681445Y308500D02*
Y311600D01*
G01X1683055D02*
Y308500D01*
G01Y310050D02*
X1681445D01*
G01X1685350Y308500D02*
Y311600D01*
X1684890Y310980D01*
G01Y308500D02*
X1685810D01*
G01X1687607Y309120D02*
X1687837Y308758D01*
X1688143Y308552D01*
X1688488Y308500D01*
X1688795Y308552D01*
X1689102Y308810D01*
X1689293Y309120D01*
X1689332Y309430D01*
X1689255Y309792D01*
X1688987Y310050D01*
X1688718Y310153D01*
X1688373D01*
G01X1688718D02*
X1688948Y310308D01*
X1689140Y310567D01*
X1689217Y310877D01*
X1689140Y311187D01*
X1688948Y311445D01*
X1688603Y311600D01*
X1688258Y311548D01*
X1687913Y311342D01*
G01X1707595Y515950D02*
Y519050D01*
G01X1709205D02*
Y515950D01*
G01Y517500D02*
X1707595D01*
G01X1710772Y518533D02*
X1711002Y518843D01*
X1711270Y518998D01*
X1711577Y519050D01*
X1711960Y518947D01*
X1712228Y518688D01*
X1712305Y518378D01*
X1712267Y518068D01*
X1712113Y517810D01*
X1711347Y517293D01*
X1711002Y516932D01*
X1710772Y516415D01*
X1710695Y515950D01*
X1712305D01*
G01X1714600Y519050D02*
X1714293Y518947D01*
X1714063Y518688D01*
X1713910Y518378D01*
X1713795Y517965D01*
X1713757Y517500D01*
X1713795Y517035D01*
X1713910Y516622D01*
X1714063Y516312D01*
X1714293Y516053D01*
X1714600Y515950D01*
X1714907Y516053D01*
X1715137Y516312D01*
X1715290Y516622D01*
X1715405Y517035D01*
X1715443Y517500D01*
X1715405Y517965D01*
X1715290Y518378D01*
X1715137Y518688D01*
X1714907Y518947D01*
X1714600Y519050D01*
G01X1728800Y86400D02*
X1722600D01*
Y89600D01*
X1728800D01*
Y86400D01*
G01X1717800D02*
X1711600D01*
Y89600D01*
X1717800D01*
Y86400D01*
G01X1748100Y136700D02*
Y102300D01*
X1736900D01*
Y136700D01*
X1740700D01*
X1742500Y134900D01*
X1744300Y136700D01*
X1748100D01*
G01X1728800Y97400D02*
X1722600D01*
Y100600D01*
X1728800D01*
Y97400D01*
G01Y91900D02*
X1722600D01*
Y95100D01*
X1728800D01*
Y91900D01*
G01X1717800Y97400D02*
X1711600D01*
Y100600D01*
X1717800D01*
Y97400D01*
G01Y91900D02*
X1711600D01*
Y95100D01*
X1717800D01*
Y91900D01*
G01X1720600Y112900D02*
X1714400D01*
Y116100D01*
X1720600D01*
Y112900D01*
G01Y107900D02*
X1714400D01*
Y111100D01*
X1720600D01*
Y107900D01*
G01X1747900Y153500D02*
Y141500D01*
X1737100D01*
Y153500D01*
X1740500D01*
X1742500Y151500D01*
X1744500Y153500D01*
X1747900D01*
G01X1720557Y140050D02*
Y137828D01*
X1720710Y137363D01*
X1721017Y137053D01*
X1721400Y136950D01*
X1721783Y137053D01*
X1722090Y137363D01*
X1722243Y137828D01*
Y140050D01*
G01X1724500Y136950D02*
Y140050D01*
X1724040Y139430D01*
G01Y136950D02*
X1724960D01*
G01X1727600D02*
X1727868Y137002D01*
X1728175Y137157D01*
X1728367Y137415D01*
X1728443Y137777D01*
X1728367Y138138D01*
X1728137Y138448D01*
X1727792Y138603D01*
X1727408D01*
X1727178Y138707D01*
X1726987Y138965D01*
X1726910Y139327D01*
X1727025Y139688D01*
X1727293Y139947D01*
X1727600Y140050D01*
X1727907Y139947D01*
X1728175Y139688D01*
X1728290Y139327D01*
X1728213Y138965D01*
X1728022Y138707D01*
X1727792Y138603D01*
X1727408D01*
X1727063Y138448D01*
X1726833Y138138D01*
X1726757Y137777D01*
X1726833Y137415D01*
X1727025Y137157D01*
X1727332Y137002D01*
X1727600Y136950D01*
G01X1713200Y149600D02*
Y143400D01*
X1710000D01*
Y149600D01*
X1713200D01*
G01X1718700D02*
Y143400D01*
X1715500D01*
Y149600D01*
X1718700D01*
G01X1714400Y136100D02*
X1720600D01*
Y132900D01*
X1714400D01*
Y136100D01*
G01Y131100D02*
X1720600D01*
Y127900D01*
X1714400D01*
Y131100D01*
G01X1720600Y117900D02*
X1714400D01*
Y121100D01*
X1720600D01*
Y117900D01*
G01X1719400Y143400D02*
Y149600D01*
X1722600D01*
Y143400D01*
X1719400D01*
G01X1723607Y162550D02*
Y160328D01*
X1723760Y159863D01*
X1724067Y159553D01*
X1724450Y159450D01*
X1724833Y159553D01*
X1725140Y159863D01*
X1725293Y160328D01*
Y162550D01*
G01X1727550Y159450D02*
Y162550D01*
X1727090Y161930D01*
G01Y159450D02*
X1728010D01*
G01X1747900Y169000D02*
Y157000D01*
X1737100D01*
Y169000D01*
X1740500D01*
X1742500Y167000D01*
X1744500Y169000D01*
X1747900D01*
G01X1726607Y157050D02*
Y154828D01*
X1726760Y154363D01*
X1727067Y154053D01*
X1727450Y153950D01*
X1727833Y154053D01*
X1728140Y154363D01*
X1728293Y154828D01*
Y157050D01*
G01X1729822Y156533D02*
X1730052Y156843D01*
X1730320Y156998D01*
X1730627Y157050D01*
X1731010Y156947D01*
X1731278Y156688D01*
X1731355Y156378D01*
X1731317Y156068D01*
X1731163Y155810D01*
X1730397Y155293D01*
X1730052Y154932D01*
X1729822Y154415D01*
X1729745Y153950D01*
X1731355D01*
G01X1713600Y165100D02*
Y158900D01*
X1710400D01*
Y165100D01*
X1713600D01*
G01X1718100D02*
Y158900D01*
X1714900D01*
Y165100D01*
X1718100D01*
G01X1719400Y158900D02*
Y165100D01*
X1722600D01*
Y158900D01*
X1719400D01*
G01X1716400Y170100D02*
X1722600D01*
Y166900D01*
X1716400D01*
Y170100D01*
G01Y154600D02*
X1722600D01*
Y151400D01*
X1716400D01*
Y154600D01*
G01X1721400Y181100D02*
X1727600D01*
Y177900D01*
X1721400D01*
Y181100D01*
G01X1727600Y173400D02*
X1721400D01*
Y176600D01*
X1727600D01*
Y173400D01*
G01X1750500Y183602D02*
Y171398D01*
X1734500D01*
Y183602D01*
X1750500D01*
G01X1737950Y199557D02*
X1740172D01*
X1740637Y199710D01*
X1740947Y200017D01*
X1741050Y200400D01*
X1740947Y200783D01*
X1740637Y201090D01*
X1740172Y201243D01*
X1737950D01*
G01X1738467Y202772D02*
X1738157Y203002D01*
X1738002Y203270D01*
X1737950Y203577D01*
X1738053Y203960D01*
X1738312Y204228D01*
X1738622Y204305D01*
X1738932Y204267D01*
X1739190Y204113D01*
X1739707Y203347D01*
X1740068Y203002D01*
X1740585Y202772D01*
X1741050Y202695D01*
Y204305D01*
G01X1739758Y205872D02*
X1739397Y206140D01*
X1739190Y206370D01*
X1739087Y206677D01*
X1739190Y206945D01*
X1739397Y207137D01*
X1739707Y207290D01*
X1740068Y207328D01*
X1740378Y207290D01*
X1740688Y207137D01*
X1740947Y206907D01*
X1741050Y206638D01*
X1740947Y206332D01*
X1740637Y206063D01*
X1740172Y205910D01*
X1739655Y205872D01*
X1738983Y205948D01*
X1738622Y206063D01*
X1738260Y206255D01*
X1738002Y206523D01*
X1737950Y206792D01*
X1738053Y207060D01*
X1738312Y207252D01*
G01X1729094Y198312D02*
X1740906D01*
Y185688D01*
X1729094D01*
Y198312D01*
G01X1727600Y181900D02*
X1721400D01*
Y185100D01*
X1727600D01*
Y181900D01*
G01X1736600Y199900D02*
X1730400D01*
Y203100D01*
X1736600D01*
Y199900D01*
G01X1715700Y187900D02*
X1709500D01*
Y191100D01*
X1715700D01*
Y187900D01*
G01X1713557Y209550D02*
Y207328D01*
X1713710Y206863D01*
X1714017Y206553D01*
X1714400Y206450D01*
X1714783Y206553D01*
X1715090Y206863D01*
X1715243Y207328D01*
Y209550D01*
G01X1716657Y207070D02*
X1716887Y206708D01*
X1717193Y206502D01*
X1717538Y206450D01*
X1717845Y206502D01*
X1718152Y206760D01*
X1718343Y207070D01*
X1718382Y207380D01*
X1718305Y207742D01*
X1718037Y208000D01*
X1717768Y208103D01*
X1717423D01*
G01X1717768D02*
X1717998Y208258D01*
X1718190Y208517D01*
X1718267Y208827D01*
X1718190Y209137D01*
X1717998Y209395D01*
X1717653Y209550D01*
X1717308Y209498D01*
X1716963Y209292D01*
G01X1719757Y207070D02*
X1719987Y206708D01*
X1720293Y206502D01*
X1720638Y206450D01*
X1720945Y206502D01*
X1721252Y206760D01*
X1721443Y207070D01*
X1721482Y207380D01*
X1721405Y207742D01*
X1721137Y208000D01*
X1720868Y208103D01*
X1720523D01*
G01X1720868D02*
X1721098Y208258D01*
X1721290Y208517D01*
X1721367Y208827D01*
X1721290Y209137D01*
X1721098Y209395D01*
X1720753Y209550D01*
X1720408Y209498D01*
X1720063Y209292D01*
G01X1720100Y195000D02*
X1722702Y192398D01*
X1726924D01*
Y204602D01*
X1713276D01*
Y192398D01*
X1717498D01*
X1720100Y195000D01*
G01X1732550Y232107D02*
X1729450D01*
Y232873D01*
X1729605Y233180D01*
X1729812Y233410D01*
X1730122Y233602D01*
X1730483Y233755D01*
X1731000Y233793D01*
X1731517Y233755D01*
X1731878Y233602D01*
X1732188Y233410D01*
X1732395Y233180D01*
X1732550Y232873D01*
Y232107D01*
G01X1731258Y235322D02*
X1730897Y235590D01*
X1730690Y235820D01*
X1730587Y236127D01*
X1730690Y236395D01*
X1730897Y236587D01*
X1731207Y236740D01*
X1731568Y236778D01*
X1731878Y236740D01*
X1732188Y236587D01*
X1732447Y236357D01*
X1732550Y236088D01*
X1732447Y235782D01*
X1732137Y235513D01*
X1731672Y235360D01*
X1731155Y235322D01*
X1730483Y235398D01*
X1730122Y235513D01*
X1729760Y235705D01*
X1729502Y235973D01*
X1729450Y236242D01*
X1729553Y236510D01*
X1729812Y236702D01*
G01X1735533Y224950D02*
Y228050D01*
X1736453D01*
X1736760Y227895D01*
X1736990Y227533D01*
X1737067Y227120D01*
X1736990Y226707D01*
X1736798Y226397D01*
X1736453Y226242D01*
X1735533D01*
G01X1740243Y227792D02*
X1740013Y227947D01*
X1739745Y228050D01*
X1739438D01*
X1739093Y227895D01*
X1738825Y227637D01*
X1738633Y227327D01*
X1738480Y226810D01*
X1738442Y226345D01*
X1738518Y225880D01*
X1738633Y225570D01*
X1738863Y225260D01*
X1739132Y225053D01*
X1739400Y224950D01*
X1739668D01*
X1739937Y225053D01*
X1740167Y225208D01*
X1740358Y225415D01*
G01X1742500Y224950D02*
Y228050D01*
X1742040Y227430D01*
G01Y224950D02*
X1742960D01*
G01X1744757Y225570D02*
X1744987Y225208D01*
X1745293Y225002D01*
X1745638Y224950D01*
X1745945Y225002D01*
X1746252Y225260D01*
X1746443Y225570D01*
X1746482Y225880D01*
X1746405Y226242D01*
X1746137Y226500D01*
X1745868Y226603D01*
X1745523D01*
G01X1745868D02*
X1746098Y226758D01*
X1746290Y227017D01*
X1746367Y227327D01*
X1746290Y227637D01*
X1746098Y227895D01*
X1745753Y228050D01*
X1745408Y227998D01*
X1745063Y227792D01*
G01X1748623Y224950D02*
X1748700Y225622D01*
X1748815Y226190D01*
X1748968Y226707D01*
X1749160Y227275D01*
X1749467Y228050D01*
X1747933D01*
G01X1735273Y252327D02*
Y233673D01*
X1742400D01*
G01X1732900Y246020D02*
Y238930D01*
X1729100D01*
Y246020D01*
G01X1732900Y246620D02*
Y239430D01*
X1729100D01*
Y246620D01*
G01X1732900Y247020D02*
Y239930D01*
X1729100D01*
Y247070D01*
X1732850D01*
G01X1733600Y248400D02*
X1727400D01*
Y251600D01*
X1733600D01*
Y248400D01*
G01X1752430Y262311D02*
X1734683D01*
Y317429D01*
X1752430D01*
G01X1742400Y255327D02*
X1738273D01*
X1735273Y252327D01*
G01X1730114Y388800D02*
Y379114D01*
X1751949D01*
X1756886Y384051D01*
Y388800D01*
G01X1730883Y408000D02*
Y411100D01*
X1731803D01*
X1732110Y410945D01*
X1732340Y410583D01*
X1732417Y410170D01*
X1732340Y409757D01*
X1732148Y409447D01*
X1731803Y409292D01*
X1730883D01*
G01X1735593Y410842D02*
X1735363Y410997D01*
X1735095Y411100D01*
X1734788D01*
X1734443Y410945D01*
X1734175Y410687D01*
X1733983Y410377D01*
X1733830Y409860D01*
X1733792Y409395D01*
X1733868Y408930D01*
X1733983Y408620D01*
X1734213Y408310D01*
X1734482Y408103D01*
X1734750Y408000D01*
X1735018D01*
X1735287Y408103D01*
X1735517Y408258D01*
X1735708Y408465D01*
G01X1737850Y408000D02*
Y411100D01*
X1737390Y410480D01*
G01Y408000D02*
X1738310D01*
G01X1740107Y408620D02*
X1740337Y408258D01*
X1740643Y408052D01*
X1740988Y408000D01*
X1741295Y408052D01*
X1741602Y408310D01*
X1741793Y408620D01*
X1741832Y408930D01*
X1741755Y409292D01*
X1741487Y409550D01*
X1741218Y409653D01*
X1740873D01*
G01X1741218D02*
X1741448Y409808D01*
X1741640Y410067D01*
X1741717Y410377D01*
X1741640Y410687D01*
X1741448Y410945D01*
X1741103Y411100D01*
X1740758Y411048D01*
X1740413Y410842D01*
G01X1744050Y408000D02*
X1744318Y408052D01*
X1744625Y408207D01*
X1744817Y408465D01*
X1744893Y408827D01*
X1744817Y409188D01*
X1744587Y409498D01*
X1744242Y409653D01*
X1743858D01*
X1743628Y409757D01*
X1743437Y410015D01*
X1743360Y410377D01*
X1743475Y410738D01*
X1743743Y410997D01*
X1744050Y411100D01*
X1744357Y410997D01*
X1744625Y410738D01*
X1744740Y410377D01*
X1744663Y410015D01*
X1744472Y409757D01*
X1744242Y409653D01*
X1743858D01*
X1743513Y409498D01*
X1743283Y409188D01*
X1743207Y408827D01*
X1743283Y408465D01*
X1743475Y408207D01*
X1743782Y408052D01*
X1744050Y408000D01*
G01X1730114Y396200D02*
Y405886D01*
X1751949D01*
X1756886Y400949D01*
Y396200D01*
G01X1765900Y111100D02*
X1772100D01*
Y107900D01*
X1765900D01*
Y111100D01*
G01X1766000Y118100D02*
X1772200D01*
Y114900D01*
X1766000D01*
Y118100D01*
G01X1765900Y106100D02*
X1772100D01*
Y102900D01*
X1765900D01*
Y106100D01*
G01X1766000Y122100D02*
X1772200D01*
Y118900D01*
X1766000D01*
Y122100D01*
G01X1772100Y122900D02*
X1765900D01*
Y126100D01*
X1772100D01*
Y122900D01*
G01Y127900D02*
X1765900D01*
Y131100D01*
X1772100D01*
Y127900D01*
G01X1770100Y149600D02*
Y143400D01*
X1766900D01*
Y149600D01*
X1770100D01*
G01X1762400Y143400D02*
Y149600D01*
X1765600D01*
Y143400D01*
X1762400D01*
G01X1765900Y136100D02*
X1772100D01*
Y132900D01*
X1765900D01*
Y136100D01*
G01X1770100Y165100D02*
Y158900D01*
X1766900D01*
Y165100D01*
X1770100D01*
G01X1762400Y158900D02*
Y165100D01*
X1765600D01*
Y158900D01*
X1762400D01*
G01X1771600Y172400D02*
X1765400D01*
Y175600D01*
X1771600D01*
Y172400D01*
G01X1758400Y175600D02*
X1764600D01*
Y172400D01*
X1758400D01*
Y175600D01*
G01X1762400Y154600D02*
X1768600D01*
Y151400D01*
X1762400D01*
Y154600D01*
G01Y170100D02*
X1768600D01*
Y166900D01*
X1762400D01*
Y170100D01*
G01X1751400Y176307D02*
X1753622D01*
X1754087Y176460D01*
X1754397Y176767D01*
X1754500Y177150D01*
X1754397Y177533D01*
X1754087Y177840D01*
X1753622Y177993D01*
X1751400D01*
G01X1751917Y179522D02*
X1751607Y179752D01*
X1751452Y180020D01*
X1751400Y180327D01*
X1751503Y180710D01*
X1751762Y180978D01*
X1752072Y181055D01*
X1752382Y181017D01*
X1752640Y180863D01*
X1753157Y180097D01*
X1753518Y179752D01*
X1754035Y179522D01*
X1754500Y179445D01*
Y181055D01*
G01Y183350D02*
X1751400D01*
X1752020Y182890D01*
G01X1754500D02*
Y183810D01*
G01X1743950Y190057D02*
X1746172D01*
X1746637Y190210D01*
X1746947Y190517D01*
X1747050Y190900D01*
X1746947Y191283D01*
X1746637Y191590D01*
X1746172Y191743D01*
X1743950D01*
G01X1746430Y193157D02*
X1746792Y193387D01*
X1746998Y193693D01*
X1747050Y194038D01*
X1746998Y194345D01*
X1746740Y194652D01*
X1746430Y194843D01*
X1746120Y194882D01*
X1745758Y194805D01*
X1745500Y194537D01*
X1745397Y194268D01*
Y193923D01*
G01Y194268D02*
X1745242Y194498D01*
X1744983Y194690D01*
X1744673Y194767D01*
X1744363Y194690D01*
X1744105Y194498D01*
X1743950Y194153D01*
X1744002Y193808D01*
X1744208Y193463D01*
G01X1745758Y196372D02*
X1745397Y196640D01*
X1745190Y196870D01*
X1745087Y197177D01*
X1745190Y197445D01*
X1745397Y197637D01*
X1745707Y197790D01*
X1746068Y197828D01*
X1746378Y197790D01*
X1746688Y197637D01*
X1746947Y197407D01*
X1747050Y197138D01*
X1746947Y196832D01*
X1746637Y196563D01*
X1746172Y196410D01*
X1745655Y196372D01*
X1744983Y196448D01*
X1744622Y196563D01*
X1744260Y196755D01*
X1744002Y197023D01*
X1743950Y197292D01*
X1744053Y197560D01*
X1744312Y197752D01*
G01X1760812Y196906D02*
Y185094D01*
X1748188D01*
Y196906D01*
X1760812D01*
G01X1774812D02*
Y185094D01*
X1762188D01*
Y196906D01*
X1774812D01*
G01X1746400Y202100D02*
X1752600D01*
Y198900D01*
X1746400D01*
Y202100D01*
G01X1753400D02*
X1759600D01*
Y198900D01*
X1753400D01*
Y202100D01*
G01X1767900D02*
X1774100D01*
Y198900D01*
X1767900D01*
Y202100D01*
G01X1764600Y179900D02*
X1758400D01*
Y183100D01*
X1764600D01*
Y179900D01*
G01X1749800Y233673D02*
X1756927D01*
Y252327D01*
X1753927Y255327D01*
X1749800D01*
G01X1765100Y239000D02*
X1759100D01*
Y251000D01*
X1765100D01*
Y239000D01*
G01X1774100D02*
X1768100D01*
Y251000D01*
X1774100D01*
Y239000D01*
G01X1785077Y317429D02*
Y262311D01*
X1767330D01*
G01X1766180Y324270D02*
X1772380D01*
Y321070D01*
X1766180D01*
Y324270D01*
G01X1744502Y326923D02*
Y333123D01*
X1747702D01*
Y326923D01*
X1744502D01*
G01X1748483Y321500D02*
Y324600D01*
X1749403D01*
X1749710Y324445D01*
X1749940Y324083D01*
X1750017Y323670D01*
X1749940Y323257D01*
X1749748Y322947D01*
X1749403Y322792D01*
X1748483D01*
G01X1751507Y324600D02*
Y322378D01*
X1751660Y321913D01*
X1751967Y321603D01*
X1752350Y321500D01*
X1752733Y321603D01*
X1753040Y321913D01*
X1753193Y322378D01*
Y324600D01*
G01X1754607Y321965D02*
X1754837Y321707D01*
X1755105Y321552D01*
X1755450Y321500D01*
X1755795Y321603D01*
X1756063Y321810D01*
X1756255Y322172D01*
X1756293Y322585D01*
X1756217Y322998D01*
X1756025Y323257D01*
X1755757Y323463D01*
X1755488Y323515D01*
X1755220Y323463D01*
X1754875Y323257D01*
X1754990Y324600D01*
X1756025D01*
G01X1751116Y327858D02*
Y327587D01*
X1754918D01*
G01X1759518D02*
X1763320D01*
Y327858D01*
G01X1767330Y317429D02*
X1785077D01*
G01X1757779Y324505D02*
X1763979D01*
Y321305D01*
X1757779D01*
Y324505D01*
G01X1748889Y354827D02*
Y360827D01*
X1760889D01*
Y354827D01*
X1748889D01*
G01Y347127D02*
Y353127D01*
X1760889D01*
Y347127D01*
X1748889D01*
G01X1757218Y343729D02*
X1751116D01*
Y343258D01*
G01X1763320Y343458D02*
Y343729D01*
G01D02*
X1759518D01*
G01X1775100Y373000D02*
Y367000D01*
X1763100D01*
Y373000D01*
X1775100D01*
G01Y366000D02*
Y360000D01*
X1763100D01*
Y366000D01*
X1775100D01*
G01X1748889Y362527D02*
Y368527D01*
X1760889D01*
Y362527D01*
X1748889D01*
G01Y370227D02*
Y376227D01*
X1760889D01*
Y370227D01*
X1748889D01*
G01X1781729Y390570D02*
Y387162D01*
X1764013D01*
G01D02*
Y390570D01*
G01Y401470D02*
Y404878D01*
X1781729D01*
Y401470D01*
G01X1795845Y136500D02*
Y139600D01*
G01X1797455D02*
Y136500D01*
G01Y138050D02*
X1795845D01*
G01X1799750Y136500D02*
Y139600D01*
X1799290Y138980D01*
G01Y136500D02*
X1800210D01*
G01X1802122Y137792D02*
X1802390Y138153D01*
X1802620Y138360D01*
X1802927Y138463D01*
X1803195Y138360D01*
X1803387Y138153D01*
X1803540Y137843D01*
X1803578Y137482D01*
X1803540Y137172D01*
X1803387Y136862D01*
X1803157Y136603D01*
X1802888Y136500D01*
X1802582Y136603D01*
X1802313Y136913D01*
X1802160Y137378D01*
X1802122Y137895D01*
X1802198Y138567D01*
X1802313Y138928D01*
X1802505Y139290D01*
X1802773Y139548D01*
X1803042Y139600D01*
X1803310Y139497D01*
X1803502Y139238D01*
G01X1774600Y149600D02*
Y143400D01*
X1771400D01*
Y149600D01*
X1774600D01*
G01Y165100D02*
Y158900D01*
X1771400D01*
Y165100D01*
X1774600D01*
G01X1776057Y187550D02*
Y185328D01*
X1776210Y184863D01*
X1776517Y184553D01*
X1776900Y184450D01*
X1777283Y184553D01*
X1777590Y184863D01*
X1777743Y185328D01*
Y187550D01*
G01X1779157Y185070D02*
X1779387Y184708D01*
X1779693Y184502D01*
X1780038Y184450D01*
X1780345Y184502D01*
X1780652Y184760D01*
X1780843Y185070D01*
X1780882Y185380D01*
X1780805Y185742D01*
X1780537Y186000D01*
X1780268Y186103D01*
X1779923D01*
G01X1780268D02*
X1780498Y186258D01*
X1780690Y186517D01*
X1780767Y186827D01*
X1780690Y187137D01*
X1780498Y187395D01*
X1780153Y187550D01*
X1779808Y187498D01*
X1779463Y187292D01*
G01X1783023Y184450D02*
X1783100Y185122D01*
X1783215Y185690D01*
X1783368Y186207D01*
X1783560Y186775D01*
X1783867Y187550D01*
X1782333D01*
G01X1779600Y197100D02*
Y190900D01*
X1776400D01*
Y197100D01*
X1779600D01*
G01X1788200Y248100D02*
Y241900D01*
X1785000D01*
Y248100D01*
X1788200D01*
G01X1782600Y239000D02*
X1776600D01*
Y251000D01*
X1782600D01*
Y239000D01*
G01X1770210Y329922D02*
X1776410D01*
Y326722D01*
X1770210D01*
Y329922D01*
G01X1773200Y324300D02*
X1779400D01*
Y321100D01*
X1773200D01*
Y324300D01*
G01X1790100Y309383D02*
X1787000D01*
Y310303D01*
X1787155Y310610D01*
X1787517Y310840D01*
X1787930Y310917D01*
X1788343Y310840D01*
X1788653Y310648D01*
X1788808Y310303D01*
Y309383D01*
G01X1787000Y312483D02*
X1790100D01*
Y314017D01*
G01X1787517Y315622D02*
X1787207Y315852D01*
X1787052Y316120D01*
X1787000Y316427D01*
X1787103Y316810D01*
X1787362Y317078D01*
X1787672Y317155D01*
X1787982Y317117D01*
X1788240Y316963D01*
X1788757Y316197D01*
X1789118Y315852D01*
X1789635Y315622D01*
X1790100Y315545D01*
Y317155D01*
G01X1777416Y341174D02*
Y334974D01*
X1774216D01*
Y341174D01*
X1777416D01*
G01X1773416D02*
Y334974D01*
X1770216D01*
Y341174D01*
X1773416D01*
G01X1776380Y342370D02*
X1770180D01*
Y345570D01*
X1776380D01*
Y342370D01*
G01X1770308Y349888D02*
X1776508D01*
Y346688D01*
X1770308D01*
Y349888D01*
G01X1776500Y354700D02*
X1770300D01*
Y357900D01*
X1776500D01*
Y354700D01*
G01X1770210Y333922D02*
X1776410D01*
Y330722D01*
X1770210D01*
Y333922D01*
G01X1781416Y341174D02*
Y334974D01*
X1778216D01*
Y341174D01*
X1781416D01*
G01X1776508Y350705D02*
X1770308D01*
Y353905D01*
X1776508D01*
Y350705D01*
G01X1774498Y381317D02*
Y384417D01*
X1775418D01*
X1775725Y384262D01*
X1775955Y383900D01*
X1776032Y383487D01*
X1775955Y383074D01*
X1775763Y382764D01*
X1775418Y382609D01*
X1774498D01*
G01X1777598Y384417D02*
Y381317D01*
X1779132D01*
G01X1781465D02*
Y384417D01*
X1781005Y383797D01*
G01Y381317D02*
X1781925D01*
G01X1795945Y455500D02*
Y458600D01*
G01X1797555D02*
Y455500D01*
G01Y457050D02*
X1795945D01*
G01X1799850Y455500D02*
Y458600D01*
X1799390Y457980D01*
G01Y455500D02*
X1800310D01*
G01X1802107Y455965D02*
X1802337Y455707D01*
X1802605Y455552D01*
X1802950Y455500D01*
X1803295Y455603D01*
X1803563Y455810D01*
X1803755Y456172D01*
X1803793Y456585D01*
X1803717Y456998D01*
X1803525Y457257D01*
X1803257Y457463D01*
X1802988Y457515D01*
X1802720Y457463D01*
X1802375Y457257D01*
X1802490Y458600D01*
X1803525D01*
G01X1869783Y99212D02*
G03I-21200J0D01*
G01X1828330Y336855D02*
X1833330Y338438D01*
X1828330Y340021D01*
G01X1833330Y342271D02*
X1828330D01*
Y343791D01*
X1828580Y344298D01*
X1829163Y344678D01*
X1829830Y344805D01*
X1830497Y344678D01*
X1830997Y344361D01*
X1831247Y343791D01*
Y342271D01*
G01X1833330Y347245D02*
X1828330D01*
Y348511D01*
X1828580Y349018D01*
X1828913Y349398D01*
X1829413Y349715D01*
X1829997Y349968D01*
X1830830Y350031D01*
X1831663Y349968D01*
X1832247Y349715D01*
X1832747Y349398D01*
X1833080Y349018D01*
X1833330Y348511D01*
Y347245D01*
G01X1830663Y354245D02*
X1830413Y354498D01*
X1829997Y354688D01*
X1829413Y354815D01*
X1828913Y354688D01*
X1828580Y354435D01*
X1828330Y353991D01*
Y352281D01*
X1833330D01*
Y354371D01*
X1832997Y354815D01*
X1832497Y355068D01*
X1831913Y355195D01*
X1831330Y355068D01*
X1830830Y354688D01*
X1830663Y354245D01*
Y352281D01*
G01X1828747Y365331D02*
X1828497Y364951D01*
X1828330Y364508D01*
Y364001D01*
X1828580Y363431D01*
X1828997Y362988D01*
X1829497Y362671D01*
X1830330Y362418D01*
X1831080Y362355D01*
X1831830Y362481D01*
X1832330Y362671D01*
X1832830Y363051D01*
X1833163Y363495D01*
X1833330Y363938D01*
Y364381D01*
X1833163Y364825D01*
X1832913Y365205D01*
X1832580Y365521D01*
G01X1833330Y369038D02*
X1833247Y368531D01*
X1832913Y368088D01*
X1832413Y367708D01*
X1831830Y367455D01*
X1831163Y367328D01*
X1830497D01*
X1829830Y367455D01*
X1829247Y367708D01*
X1828747Y368088D01*
X1828413Y368531D01*
X1828330Y369038D01*
X1828413Y369545D01*
X1828747Y369988D01*
X1829247Y370368D01*
X1829830Y370621D01*
X1830497Y370748D01*
X1831163D01*
X1831830Y370621D01*
X1832413Y370368D01*
X1832913Y369988D01*
X1833247Y369545D01*
X1833330Y369038D01*
G01Y372681D02*
X1828330D01*
X1833330Y375595D01*
X1828330D01*
G01X1833330Y377781D02*
X1828330D01*
X1833330Y380695D01*
X1828330D01*
G01X1869782Y481693D02*
G03I-21200J0D01*
G01X1843883Y124120D02*
X1844075Y123810D01*
X1844305Y123603D01*
X1844573Y123500D01*
X1844880Y123603D01*
X1845110Y123810D01*
X1845340Y124120D01*
X1845417Y124533D01*
Y126600D01*
G01X1847750Y123500D02*
Y126600D01*
X1847290Y125980D01*
G01Y123500D02*
X1848210D01*
G01X1850122Y124792D02*
X1850390Y125153D01*
X1850620Y125360D01*
X1850927Y125463D01*
X1851195Y125360D01*
X1851387Y125153D01*
X1851540Y124843D01*
X1851578Y124482D01*
X1851540Y124172D01*
X1851387Y123862D01*
X1851157Y123603D01*
X1850888Y123500D01*
X1850582Y123603D01*
X1850313Y123913D01*
X1850160Y124378D01*
X1850122Y124895D01*
X1850198Y125567D01*
X1850313Y125928D01*
X1850505Y126290D01*
X1850773Y126548D01*
X1851042Y126600D01*
X1851310Y126497D01*
X1851502Y126238D01*
G01X1837185Y198898D02*
Y381969D01*
X1865729D01*
Y198898D01*
X1837185D01*
G01X1837640Y384100D02*
X1837832Y383790D01*
X1838062Y383583D01*
X1838330Y383480D01*
X1838637Y383583D01*
X1838867Y383790D01*
X1839097Y384100D01*
X1839174Y384513D01*
Y386580D01*
G01X1841507Y383480D02*
Y386580D01*
X1841047Y385960D01*
G01Y383480D02*
X1841967D01*
G01X1844607D02*
Y386580D01*
X1844147Y385960D01*
G01Y383480D02*
X1845067D01*
G01X1850564Y420138D02*
Y426338D01*
X1853764D01*
Y420138D01*
X1850564D01*
G01X1835564D02*
Y426338D01*
X1838764D01*
Y420138D01*
X1835564D01*
G01X1845564D02*
Y426338D01*
X1848764D01*
Y420138D01*
X1845564D01*
G01X1840564D02*
Y426338D01*
X1843764D01*
Y420138D01*
X1840564D01*
G01X1845483Y455620D02*
X1845675Y455310D01*
X1845905Y455103D01*
X1846173Y455000D01*
X1846480Y455103D01*
X1846710Y455310D01*
X1846940Y455620D01*
X1847017Y456033D01*
Y458100D01*
G01X1849350Y455000D02*
Y458100D01*
X1848890Y457480D01*
G01Y455000D02*
X1849810D01*
G01X1851607Y455465D02*
X1851837Y455207D01*
X1852105Y455052D01*
X1852450Y455000D01*
X1852795Y455103D01*
X1853063Y455310D01*
X1853255Y455672D01*
X1853293Y456085D01*
X1853217Y456498D01*
X1853025Y456757D01*
X1852757Y456963D01*
X1852488Y457015D01*
X1852220Y456963D01*
X1851875Y456757D01*
X1851990Y458100D01*
X1853025D01*
G01X1869154Y732480D02*
X1866054D01*
Y733400D01*
X1866209Y733707D01*
X1866571Y733937D01*
X1866984Y734014D01*
X1867397Y733937D01*
X1867707Y733745D01*
X1867862Y733400D01*
Y732480D01*
G01X1869257Y735657D02*
X1866054Y737037D01*
G01X1869154Y738565D02*
X1866054D01*
X1869154Y740329D01*
X1866054D01*
G01X1869257Y742547D02*
X1869206Y742470D01*
X1869102D01*
X1869051Y742547D01*
X1869102Y742624D01*
X1869206D01*
X1869257Y742547D01*
G01X1867862D02*
X1867811Y742470D01*
X1867707D01*
X1867656Y742547D01*
X1867707Y742624D01*
X1867811D01*
X1867862Y742547D01*
G01X1869154Y744804D02*
X1866054D01*
Y745570D01*
X1866209Y745877D01*
X1866416Y746107D01*
X1866726Y746299D01*
X1867087Y746452D01*
X1867604Y746490D01*
X1868121Y746452D01*
X1868482Y746299D01*
X1868792Y746107D01*
X1868999Y745877D01*
X1869154Y745570D01*
Y744804D01*
G01Y747789D02*
X1866054Y748747D01*
X1869154Y749705D01*
G01X1868069Y749360D02*
Y748134D01*
G01X1869154Y751119D02*
X1866054D01*
Y752575D01*
G01X1867552Y752039D02*
Y751119D01*
G01X1866054Y754947D02*
X1866157Y754640D01*
X1866416Y754410D01*
X1866726Y754257D01*
X1867139Y754142D01*
X1867604Y754104D01*
X1868069Y754142D01*
X1868482Y754257D01*
X1868792Y754410D01*
X1869051Y754640D01*
X1869154Y754947D01*
X1869051Y755254D01*
X1868792Y755484D01*
X1868482Y755637D01*
X1868069Y755752D01*
X1867604Y755790D01*
X1867139Y755752D01*
X1866726Y755637D01*
X1866416Y755484D01*
X1866157Y755254D01*
X1866054Y754947D01*
G01Y758047D02*
X1869154D01*
G01X1866054Y757165D02*
Y758929D01*
G01X1869154Y760380D02*
X1866054D01*
Y761300D01*
X1866209Y761607D01*
X1866571Y761837D01*
X1866984Y761914D01*
X1867397Y761837D01*
X1867707Y761645D01*
X1867862Y761300D01*
Y760380D01*
G01X1867501Y764554D02*
X1867346Y764707D01*
X1867087Y764822D01*
X1866726Y764899D01*
X1866416Y764822D01*
X1866209Y764669D01*
X1866054Y764400D01*
Y763365D01*
X1869154D01*
Y764630D01*
X1868947Y764899D01*
X1868637Y765052D01*
X1868276Y765129D01*
X1867914Y765052D01*
X1867604Y764822D01*
X1867501Y764554D01*
Y763365D01*
G01X1869154Y767347D02*
X1866054D01*
X1866674Y766887D01*
G01X1869154D02*
Y767807D01*
G01Y769489D02*
X1866054Y770447D01*
X1869154Y771405D01*
G01X1868069Y771060D02*
Y769834D01*
G01X1869154Y772819D02*
X1866054D01*
Y774275D01*
G01X1867552Y773739D02*
Y772819D01*
G01X1866054Y776647D02*
X1866157Y776340D01*
X1866416Y776110D01*
X1866726Y775957D01*
X1867139Y775842D01*
X1867604Y775804D01*
X1868069Y775842D01*
X1868482Y775957D01*
X1868792Y776110D01*
X1869051Y776340D01*
X1869154Y776647D01*
X1869051Y776954D01*
X1868792Y777184D01*
X1868482Y777337D01*
X1868069Y777452D01*
X1867604Y777490D01*
X1867139Y777452D01*
X1866726Y777337D01*
X1866416Y777184D01*
X1866157Y776954D01*
X1866054Y776647D01*
M02*
